FILE_TYPE = MACRO_DRAWING;
SET COLOR_WIRE YELLOW;
SET COLOR_PROP ORANGE;
SET COLOR_DOT WHITE;
SET COLOR_ARC YELLOW;
SET COLOR_BODY GREEN;
SET COLOR_NOTE PURPLE;
SET PROP_DISPLAY VALUE;
SET PAGE_NUMBER P188;
FORCEADD UNIVERSAL_GND..1
(-7925 4100);
FORCEPROP 3 LASTPIN (-7925 4150) SIG_NAME GND\g
J 0
(-7915 4160);
DISPLAY 0.659574 (-7915 4160);
PAINT MONO (-7915 4160);
DISPLAY INVISIBLE (-7915 4160);
FORCEPROP 2 LAST CDS_LIB pure_quanta_power
J 0
(-7925 4100);
DISPLAY INVISIBLE (-7925 4100);
FORCEPROP 1 LAST PATH I1
J 0
(-7850 4100);
DISPLAY 0.872340 (-7850 4100);
PAINT AQUA (-7850 4100);
DISPLAY INVISIBLE (-7850 4100);
FORCEPROP 1 LAST HDL_POWER GND
J 1
(-7900 4025);
DISPLAY 0.872340 (-7900 4025);
PAINT GREEN (-7900 4025);
DISPLAY INVISIBLE (-7900 4025);
FORCEADD Q_RES..1
(-7275 4350);
FORCEPROP 1 LAST LOCATION PR202
J 0
(-7300 4400);
DISPLAY 0.489362 (-7300 4400);
PAINT SKYBLUE (-7300 4400);
FORCEPROP 0 LAST $SEC 1
J 0
(-7275 4425);
DISPLAY 0.680851 (-7275 4425);
PAINT MONO (-7275 4425);
DISPLAY INVISIBLE (-7275 4425);
FORCEPROP 0 LAST CDS_SEC 1
J 0
(-7275 4425);
DISPLAY 1.021277 (-7275 4425);
DISPLAY INVISIBLE (-7275 4425);
FORCEPROP 1 LASTPIN (-7375 4350) $PN 1
J 0
(-7363 4362);
DISPLAY 0.489362 (-7363 4362);
PAINT MONO (-7363 4362);
FORCEPROP 1 LASTPIN (-7175 4350) $PN 2
J 0
(-7213 4362);
DISPLAY 0.489362 (-7213 4362);
PAINT MONO (-7213 4362);
FORCEPROP 1 LAST WATTAGE 1/16W
J 0
(-7175 4250);
DISPLAY 0.489362 (-7175 4250);
PAINT SKYBLUE (-7175 4250);
FORCEPROP 1 LAST MATERIAL EMPTY
J 0
(-7575 4250);
DISPLAY 0.489362 (-7575 4250);
PAINT RED (-7575 4250);
FORCEPROP 1 LAST TOLERANCE 1%
J 0
(-7150 4375);
DISPLAY 0.489362 (-7150 4375);
PAINT SKYBLUE (-7150 4375);
FORCEPROP 1 LAST VALUE 8.87K
J 2
(-7400 4375);
DISPLAY 0.489362 (-7400 4375);
PAINT SKYBLUE (-7400 4375);
FORCEPROP 1 LAST PART_NUMBER CS28872FB01
J 0
(-7575 4300);
DISPLAY 0.489362 (-7575 4300);
PAINT SKYBLUE (-7575 4300);
FORCEPROP 1 LAST PACK_TYPE 0402LF
J 0
(-7175 4300);
DISPLAY 0.489362 (-7175 4300);
PAINT SKYBLUE (-7175 4300);
FORCEPROP 2 LAST CDS_LIB pure_quanta
J 0
(-7275 4350);
DISPLAY INVISIBLE (-7275 4350);
FORCEPROP 1 LAST PATH I11
J 0
(-7325 4500);
DISPLAY 0.978723 (-7325 4500);
PAINT WHITE (-7325 4500);
DISPLAY INVISIBLE (-7325 4500);
FORCEADD UNIVERSAL_GND..1
(-5550 3925);
FORCEPROP 3 LASTPIN (-5550 3975) SIG_NAME GND\g
J 0
(-5540 3985);
DISPLAY 0.659574 (-5540 3985);
PAINT MONO (-5540 3985);
DISPLAY INVISIBLE (-5540 3985);
FORCEPROP 2 LAST CDS_LIB pure_quanta_power
J 0
(-5550 3925);
DISPLAY INVISIBLE (-5550 3925);
FORCEPROP 1 LAST PATH I15
J 0
(-5475 3925);
DISPLAY 0.872340 (-5475 3925);
PAINT AQUA (-5475 3925);
DISPLAY INVISIBLE (-5475 3925);
FORCEPROP 1 LAST HDL_POWER GND
J 1
(-5525 3850);
DISPLAY 0.872340 (-5525 3850);
PAINT GREEN (-5525 3850);
DISPLAY INVISIBLE (-5525 3850);
FORCEADD Q_RES..1
(-4325 3550);
FORCEPROP 1 LAST LOCATION PR204
J 0
(-4350 3600);
DISPLAY 0.489362 (-4350 3600);
PAINT SKYBLUE (-4350 3600);
FORCEPROP 0 LAST $SEC 1
J 0
(-4325 3625);
DISPLAY 0.680851 (-4325 3625);
PAINT MONO (-4325 3625);
DISPLAY INVISIBLE (-4325 3625);
FORCEPROP 0 LAST CDS_SEC 1
J 0
(-4325 3625);
DISPLAY 1.021277 (-4325 3625);
DISPLAY INVISIBLE (-4325 3625);
FORCEPROP 1 LASTPIN (-4425 3550) $PN 1
J 0
(-4413 3562);
DISPLAY 0.489362 (-4413 3562);
PAINT MONO (-4413 3562);
FORCEPROP 1 LASTPIN (-4225 3550) $PN 2
J 0
(-4263 3562);
DISPLAY 0.489362 (-4263 3562);
PAINT MONO (-4263 3562);
FORCEPROP 1 LAST WATTAGE 1/16W
J 0
(-4225 3500);
DISPLAY 0.489362 (-4225 3500);
PAINT SKYBLUE (-4225 3500);
FORCEPROP 1 LAST MATERIAL CHIP
J 0
(-4575 3450);
DISPLAY 0.489362 (-4575 3450);
PAINT SKYBLUE (-4575 3450);
FORCEPROP 1 LAST TOLERANCE 5%
J 0
(-4200 3575);
DISPLAY 0.489362 (-4200 3575);
PAINT SKYBLUE (-4200 3575);
FORCEPROP 1 LAST VALUE 0
J 2
(-4450 3575);
DISPLAY 0.489362 (-4450 3575);
PAINT SKYBLUE (-4450 3575);
FORCEPROP 1 LAST PART_NUMBER CS00002JB38
J 0
(-4575 3500);
DISPLAY 0.489362 (-4575 3500);
PAINT SKYBLUE (-4575 3500);
FORCEPROP 1 LAST PACK_TYPE 0402LF
J 0
(-4225 3450);
DISPLAY 0.489362 (-4225 3450);
PAINT SKYBLUE (-4225 3450);
FORCEPROP 2 LAST CDS_LIB pure_quanta
J 0
(-4325 3550);
DISPLAY INVISIBLE (-4325 3550);
FORCEPROP 1 LAST PATH I17
J 0
(-4375 3700);
DISPLAY 0.978723 (-4375 3700);
PAINT WHITE (-4375 3700);
DISPLAY INVISIBLE (-4375 3700);
FORCEADD Q_RES..1
(-4700 5000);
FORCEPROP 1 LAST LOCATION PR203
J 0
(-4725 5050);
DISPLAY 0.489362 (-4725 5050);
PAINT SKYBLUE (-4725 5050);
FORCEPROP 0 LAST $SEC 1
J 0
(-4675 5075);
DISPLAY 0.680851 (-4675 5075);
PAINT MONO (-4675 5075);
DISPLAY INVISIBLE (-4675 5075);
FORCEPROP 0 LAST CDS_SEC 1
J 0
(-4675 5075);
DISPLAY 1.021277 (-4675 5075);
DISPLAY INVISIBLE (-4675 5075);
FORCEPROP 1 LASTPIN (-4800 5000) $PN 1
J 0
(-4788 5012);
DISPLAY 0.489362 (-4788 5012);
PAINT MONO (-4788 5012);
FORCEPROP 1 LASTPIN (-4600 5000) $PN 2
J 0
(-4638 5012);
DISPLAY 0.489362 (-4638 5012);
PAINT MONO (-4638 5012);
FORCEPROP 1 LAST PACK_TYPE 0402LF
J 0
(-4600 4900);
DISPLAY 0.489362 (-4600 4900);
PAINT SKYBLUE (-4600 4900);
FORCEPROP 1 LAST TOLERANCE 1%
J 0
(-4600 5025);
DISPLAY 0.489362 (-4600 5025);
PAINT SKYBLUE (-4600 5025);
FORCEPROP 1 LAST MATERIAL CHIP
J 0
(-4950 4900);
DISPLAY 0.489362 (-4950 4900);
PAINT SKYBLUE (-4950 4900);
FORCEPROP 1 LAST WATTAGE 1/16W
J 0
(-4600 4950);
DISPLAY 0.489362 (-4600 4950);
PAINT SKYBLUE (-4600 4950);
FORCEPROP 1 LAST VALUE 4.7
J 2
(-4800 5025);
DISPLAY 0.489362 (-4800 5025);
PAINT SKYBLUE (-4800 5025);
FORCEPROP 1 LAST PART_NUMBER CS-4702FB19
J 0
(-4950 4950);
DISPLAY 0.489362 (-4950 4950);
PAINT SKYBLUE (-4950 4950);
FORCEPROP 1 LAST PATH I18
J 0
(-4750 5150);
DISPLAY 0.978723 (-4750 5150);
PAINT WHITE (-4750 5150);
DISPLAY INVISIBLE (-4750 5150);
FORCEPROP 2 LAST CDS_LIB pure_quanta
J 0
(-4700 5000);
DISPLAY INVISIBLE (-4700 5000);
FORCEADD Q_CAP..1
(-4975 5525);
FORCEPROP 1 LAST LOCATION PC310_5
J 0
(-4925 5625);
DISPLAY 0.489362 (-4925 5625);
PAINT SKYBLUE (-4925 5625);
FORCEPROP 0 LAST $SEC 1
J 0
(-4925 5650);
DISPLAY 0.680851 (-4925 5650);
PAINT MONO (-4925 5650);
DISPLAY INVISIBLE (-4925 5650);
FORCEPROP 0 LAST CDS_SEC 1
J 0
(-4925 5650);
DISPLAY 1.021277 (-4925 5650);
DISPLAY INVISIBLE (-4925 5650);
FORCEPROP 1 LASTPIN (-4975 5625) $PN 1
J 0
(-4965 5605);
DISPLAY 0.489362 (-4965 5605);
PAINT MONO (-4965 5605);
FORCEPROP 1 LASTPIN (-4975 5425) $PN 2
J 0
(-4965 5405);
DISPLAY 0.489362 (-4965 5405);
PAINT MONO (-4965 5405);
FORCEPROP 1 LAST MATERIAL X6S
J 0
(-4925 5425);
DISPLAY 0.489362 (-4925 5425);
PAINT SKYBLUE (-4925 5425);
FORCEPROP 1 LAST TOLERANCE 10%
J 0
(-4925 5475);
DISPLAY 0.489362 (-4925 5475);
PAINT SKYBLUE (-4925 5475);
FORCEPROP 1 LAST VALUE 1UF
J 0
(-4925 5575);
DISPLAY 0.489362 (-4925 5575);
PAINT SKYBLUE (-4925 5575);
FORCEPROP 1 LAST PART_NUMBER CH5104KEB02
J 0
(-4925 5375);
DISPLAY 0.489362 (-4925 5375);
PAINT SKYBLUE (-4925 5375);
FORCEPROP 1 LAST VOLTAGE 25V
J 0
(-4925 5525);
DISPLAY 0.489362 (-4925 5525);
PAINT SKYBLUE (-4925 5525);
FORCEPROP 1 LAST PACK_TYPE C0402
J 0
(-4925 5325);
DISPLAY 0.489362 (-4925 5325);
PAINT SKYBLUE (-4925 5325);
FORCEPROP 2 LAST CDS_LIB pure_quanta
J 0
(-4975 5525);
DISPLAY INVISIBLE (-4975 5525);
FORCEPROP 1 LAST PATH I19
J 0
(-4925 5675);
DISPLAY 0.978723 (-4925 5675);
PAINT WHITE (-4925 5675);
DISPLAY INVISIBLE (-4925 5675);
FORCEADD Q_CAP..1
(-7925 4375);
FORCEPROP 1 LAST LOCATION PC306_5
J 0
(-7875 4475);
DISPLAY 0.489362 (-7875 4475);
PAINT SKYBLUE (-7875 4475);
FORCEPROP 0 LAST $SEC 1
J 0
(-7875 4500);
DISPLAY 0.680851 (-7875 4500);
PAINT MONO (-7875 4500);
DISPLAY INVISIBLE (-7875 4500);
FORCEPROP 0 LAST CDS_SEC 1
J 0
(-7875 4500);
DISPLAY 1.021277 (-7875 4500);
DISPLAY INVISIBLE (-7875 4500);
FORCEPROP 1 LASTPIN (-7925 4475) $PN 1
J 0
(-7915 4455);
DISPLAY 0.489362 (-7915 4455);
PAINT MONO (-7915 4455);
FORCEPROP 1 LASTPIN (-7925 4275) $PN 2
J 0
(-7915 4255);
DISPLAY 0.489362 (-7915 4255);
PAINT MONO (-7915 4255);
FORCEPROP 1 LAST MATERIAL X7R
J 0
(-7875 4275);
DISPLAY 0.489362 (-7875 4275);
PAINT SKYBLUE (-7875 4275);
FORCEPROP 1 LAST TOLERANCE 10%
J 0
(-7875 4325);
DISPLAY 0.489362 (-7875 4325);
PAINT SKYBLUE (-7875 4325);
FORCEPROP 1 LAST VALUE 0.1UF
J 0
(-7875 4425);
DISPLAY 0.489362 (-7875 4425);
PAINT SKYBLUE (-7875 4425);
FORCEPROP 1 LAST PART_NUMBER CH4104K1B00
J 0
(-7875 4225);
DISPLAY 0.489362 (-7875 4225);
PAINT SKYBLUE (-7875 4225);
FORCEPROP 1 LAST VOLTAGE 25V
J 0
(-7875 4375);
DISPLAY 0.489362 (-7875 4375);
PAINT SKYBLUE (-7875 4375);
FORCEPROP 1 LAST PACK_TYPE 0402
J 0
(-7875 4175);
DISPLAY 0.489362 (-7875 4175);
PAINT SKYBLUE (-7875 4175);
FORCEPROP 2 LAST CDS_LIB pure_quanta
J 0
(-7925 4375);
DISPLAY INVISIBLE (-7925 4375);
FORCEPROP 1 LAST PATH I2
J 0
(-7875 4525);
DISPLAY 0.978723 (-7875 4525);
PAINT WHITE (-7875 4525);
DISPLAY INVISIBLE (-7875 4525);
FORCEADD Q_CAP..1
(-4650 5525);
FORCEPROP 1 LAST LOCATION PC311_5
J 0
(-4600 5625);
DISPLAY 0.489362 (-4600 5625);
PAINT SKYBLUE (-4600 5625);
FORCEPROP 0 LAST $SEC 1
J 0
(-4600 5650);
DISPLAY 0.680851 (-4600 5650);
PAINT MONO (-4600 5650);
DISPLAY INVISIBLE (-4600 5650);
FORCEPROP 0 LAST CDS_SEC 1
J 0
(-4600 5650);
DISPLAY 1.021277 (-4600 5650);
DISPLAY INVISIBLE (-4600 5650);
FORCEPROP 1 LASTPIN (-4650 5625) $PN 1
J 0
(-4640 5605);
DISPLAY 0.489362 (-4640 5605);
PAINT MONO (-4640 5605);
FORCEPROP 1 LASTPIN (-4650 5425) $PN 2
J 0
(-4640 5405);
DISPLAY 0.489362 (-4640 5405);
PAINT MONO (-4640 5405);
FORCEPROP 1 LAST MATERIAL X6S
J 0
(-4600 5425);
DISPLAY 0.489362 (-4600 5425);
PAINT SKYBLUE (-4600 5425);
FORCEPROP 1 LAST TOLERANCE 10%
J 0
(-4600 5475);
DISPLAY 0.489362 (-4600 5475);
PAINT SKYBLUE (-4600 5475);
FORCEPROP 1 LAST VALUE 10UF
J 0
(-4600 5575);
DISPLAY 0.489362 (-4600 5575);
PAINT SKYBLUE (-4600 5575);
FORCEPROP 1 LAST PART_NUMBER CH6104KEA00
J 0
(-4600 5375);
DISPLAY 0.489362 (-4600 5375);
PAINT SKYBLUE (-4600 5375);
FORCEPROP 1 LAST VOLTAGE 25V
J 0
(-4600 5525);
DISPLAY 0.489362 (-4600 5525);
PAINT SKYBLUE (-4600 5525);
FORCEPROP 1 LAST PACK_TYPE C0805
J 0
(-4600 5325);
DISPLAY 0.489362 (-4600 5325);
PAINT SKYBLUE (-4600 5325);
FORCEPROP 2 LAST CDS_LIB pure_quanta
J 0
(-4650 5525);
DISPLAY INVISIBLE (-4650 5525);
FORCEPROP 1 LAST PATH I20
J 0
(-4600 5675);
DISPLAY 0.978723 (-4600 5675);
PAINT WHITE (-4600 5675);
DISPLAY INVISIBLE (-4600 5675);
FORCEADD Q_CAP..1
(-4325 5525);
FORCEPROP 1 LAST LOCATION PC312_5
J 0
(-4275 5625);
DISPLAY 0.489362 (-4275 5625);
PAINT SKYBLUE (-4275 5625);
FORCEPROP 0 LAST $SEC 1
J 0
(-4275 5650);
DISPLAY 0.680851 (-4275 5650);
PAINT MONO (-4275 5650);
DISPLAY INVISIBLE (-4275 5650);
FORCEPROP 0 LAST CDS_SEC 1
J 0
(-4275 5650);
DISPLAY 1.021277 (-4275 5650);
DISPLAY INVISIBLE (-4275 5650);
FORCEPROP 1 LASTPIN (-4325 5625) $PN 1
J 0
(-4315 5605);
DISPLAY 0.489362 (-4315 5605);
PAINT MONO (-4315 5605);
FORCEPROP 1 LASTPIN (-4325 5425) $PN 2
J 0
(-4315 5405);
DISPLAY 0.489362 (-4315 5405);
PAINT MONO (-4315 5405);
FORCEPROP 1 LAST MATERIAL X6S
J 0
(-4275 5425);
DISPLAY 0.489362 (-4275 5425);
PAINT SKYBLUE (-4275 5425);
FORCEPROP 1 LAST TOLERANCE 10%
J 0
(-4275 5475);
DISPLAY 0.489362 (-4275 5475);
PAINT SKYBLUE (-4275 5475);
FORCEPROP 1 LAST VALUE 10UF
J 0
(-4275 5575);
DISPLAY 0.489362 (-4275 5575);
PAINT SKYBLUE (-4275 5575);
FORCEPROP 1 LAST PART_NUMBER CH6104KEA00
J 0
(-4275 5375);
DISPLAY 0.489362 (-4275 5375);
PAINT SKYBLUE (-4275 5375);
FORCEPROP 1 LAST VOLTAGE 25V
J 0
(-4275 5525);
DISPLAY 0.489362 (-4275 5525);
PAINT SKYBLUE (-4275 5525);
FORCEPROP 1 LAST PACK_TYPE C0805
J 0
(-4275 5325);
DISPLAY 0.489362 (-4275 5325);
PAINT SKYBLUE (-4275 5325);
FORCEPROP 2 LAST CDS_LIB pure_quanta
J 0
(-4325 5525);
DISPLAY INVISIBLE (-4325 5525);
FORCEPROP 1 LAST PATH I21
J 0
(-4275 5675);
DISPLAY 0.978723 (-4275 5675);
PAINT WHITE (-4275 5675);
DISPLAY INVISIBLE (-4275 5675);
FORCEADD Q_INDUCTOR4P_14..1
(-2875 4525);
FORCEPROP 1 LAST LOCATION PL33
J 0
(-3100 4780);
DISPLAY 0.489362 (-3100 4780);
PAINT SKYBLUE (-3100 4780);
FORCEPROP 0 LAST $SEC 1
J 0
(-3100 4925);
DISPLAY 0.680851 (-3100 4925);
PAINT MONO (-3100 4925);
DISPLAY INVISIBLE (-3100 4925);
FORCEPROP 0 LAST CDS_SEC 1
J 0
(-3100 4925);
DISPLAY 1.021277 (-3100 4925);
DISPLAY INVISIBLE (-3100 4925);
FORCEPROP 0 LASTPIN (-3275 4650) $PN 1
J 2
(-3285 4660);
DISPLAY 0.489362 (-3285 4660);
PAINT MONO (-3285 4660);
FORCEPROP 0 LASTPIN (-3275 4400) $PN 2
J 2
(-3285 4410);
DISPLAY 0.489362 (-3285 4410);
PAINT MONO (-3285 4410);
FORCEPROP 0 LASTPIN (-2475 4400) $PN 3
J 0
(-2465 4410);
DISPLAY 0.489362 (-2465 4410);
PAINT MONO (-2465 4410);
FORCEPROP 0 LASTPIN (-2475 4650) $PN 4
J 0
(-2465 4660);
DISPLAY 0.489362 (-2465 4660);
PAINT MONO (-2465 4660);
FORCEPROP 2 LAST PART_TYPE SMLF
J 0
(-3100 4875);
DISPLAY 1.021277 (-3100 4875);
FORCEPROP 1 LAST MATERIAL IND
J 0
(-3100 4735);
DISPLAY 0.489362 (-3100 4735);
PAINT SKYBLUE (-3100 4735);
FORCEPROP 2 LAST VALUE 150NH
J 0
(-3100 4825);
DISPLAY 0.489362 (-3100 4825);
PAINT SKYBLUE (-3100 4825);
FORCEPROP 1 LAST PART_NUMBER CV+15^0TZ04
J 0
(-3100 4685);
DISPLAY 0.489362 (-3100 4685);
PAINT SKYBLUE (-3100 4685);
FORCEPROP 2 LAST CDS_LIB pure_quanta
J 0
(-2875 4525);
DISPLAY INVISIBLE (-2875 4525);
FORCEPROP 1 LAST NEEDS_NO_SIZE TRUE
J 0
(-2875 4525);
DISPLAY 0.468085 (-2875 4525);
PAINT GREEN (-2875 4525);
DISPLAY INVISIBLE (-2875 4525);
FORCEPROP 1 LAST PATH I23
J 0
(-2675 4680);
DISPLAY 0.723404 (-2675 4680);
PAINT GREEN (-2675 4680);
DISPLAY INVISIBLE (-2675 4680);
FORCEADD UNIVERSAL_GND..1
(-4025 5175);
FORCEPROP 3 LASTPIN (-4025 5225) SIG_NAME GND\g
J 0
(-4015 5235);
DISPLAY 0.659574 (-4015 5235);
PAINT MONO (-4015 5235);
DISPLAY INVISIBLE (-4015 5235);
FORCEPROP 2 LAST CDS_LIB pure_quanta_power
J 0
(-4025 5175);
DISPLAY INVISIBLE (-4025 5175);
FORCEPROP 1 LAST PATH I24
J 0
(-3950 5175);
DISPLAY 0.872340 (-3950 5175);
PAINT AQUA (-3950 5175);
DISPLAY INVISIBLE (-3950 5175);
FORCEPROP 1 LAST HDL_POWER GND
J 1
(-4000 5100);
DISPLAY 0.872340 (-4000 5100);
PAINT GREEN (-4000 5100);
DISPLAY INVISIBLE (-4000 5100);
FORCEADD Q_CAP..1
(-4025 5525);
FORCEPROP 1 LAST LOCATION PC313_5
J 0
(-3975 5625);
DISPLAY 0.489362 (-3975 5625);
PAINT SKYBLUE (-3975 5625);
FORCEPROP 0 LAST $SEC 1
J 0
(-3975 5650);
DISPLAY 0.680851 (-3975 5650);
PAINT MONO (-3975 5650);
DISPLAY INVISIBLE (-3975 5650);
FORCEPROP 0 LAST CDS_SEC 1
J 0
(-3975 5650);
DISPLAY 1.021277 (-3975 5650);
DISPLAY INVISIBLE (-3975 5650);
FORCEPROP 1 LASTPIN (-4025 5625) $PN 1
J 0
(-4015 5605);
DISPLAY 0.489362 (-4015 5605);
PAINT MONO (-4015 5605);
FORCEPROP 1 LASTPIN (-4025 5425) $PN 2
J 0
(-4015 5405);
DISPLAY 0.489362 (-4015 5405);
PAINT MONO (-4015 5405);
FORCEPROP 1 LAST MATERIAL X6S
J 0
(-3975 5425);
DISPLAY 0.489362 (-3975 5425);
PAINT SKYBLUE (-3975 5425);
FORCEPROP 1 LAST TOLERANCE 10%
J 0
(-3975 5475);
DISPLAY 0.489362 (-3975 5475);
PAINT SKYBLUE (-3975 5475);
FORCEPROP 1 LAST VALUE 10UF
J 0
(-3975 5575);
DISPLAY 0.489362 (-3975 5575);
PAINT SKYBLUE (-3975 5575);
FORCEPROP 1 LAST PART_NUMBER CH6104KEA00
J 0
(-3975 5375);
DISPLAY 0.489362 (-3975 5375);
PAINT SKYBLUE (-3975 5375);
FORCEPROP 1 LAST VOLTAGE 25V
J 0
(-3975 5525);
DISPLAY 0.489362 (-3975 5525);
PAINT SKYBLUE (-3975 5525);
FORCEPROP 1 LAST PACK_TYPE C0805
J 0
(-3975 5325);
DISPLAY 0.489362 (-3975 5325);
PAINT SKYBLUE (-3975 5325);
FORCEPROP 2 LAST CDS_LIB pure_quanta
J 0
(-4025 5525);
DISPLAY INVISIBLE (-4025 5525);
FORCEPROP 1 LAST PATH I25
J 0
(-3975 5675);
DISPLAY 0.978723 (-3975 5675);
PAINT WHITE (-3975 5675);
DISPLAY INVISIBLE (-3975 5675);
FORCEADD VCC_CORE..1
(-4025 5825);
FORCEPROP 3 LASTPIN (-4025 5775) SIG_NAME SW_P12V_STBY_PVDDCR_CPU0_P1_FLT\g
J 0
(-4015 5785);
DISPLAY 0.659574 (-4015 5785);
PAINT MONO (-4015 5785);
DISPLAY INVISIBLE (-4015 5785);
FORCEPROP 1 LAST HDL_POWER SW_P12V_STBY_PVDDCR_CPU0_P1_FLT
J 1
(-4025 5875);
DISPLAY 0.489362 (-4025 5875);
PAINT GREEN (-4025 5875);
FORCEPROP 2 LAST CDS_LIB pure_quanta_power
J 0
(-4025 5825);
DISPLAY INVISIBLE (-4025 5825);
FORCEPROP 1 LAST PATH I26
J 0
(-3975 5850);
DISPLAY 0.872340 (-3975 5850);
PAINT AQUA (-3975 5850);
DISPLAY INVISIBLE (-3975 5850);
FORCEADD OFFPAGE..3
(-1925 4400);
FORCEPROP 2 LAST $XR0 187 
J 0
(-1711 4400);
DISPLAY 0.638298 (-1711 4400);
PAINT MONO (-1711 4400);
FORCEPROP 1 LAST COMMENT_BODY TRUE
J 0
(-1975 4300);
DISPLAY 0.872340 (-1975 4300);
PAINT GREEN (-1975 4300);
DISPLAY INVISIBLE (-1975 4300);
FORCEPROP 1 LAST OFFPAGE TRUE
J 0
(-1600 4275);
DISPLAY 0.872340 (-1600 4275);
PAINT GREEN (-1600 4275);
DISPLAY INVISIBLE (-1600 4275);
FORCEPROP 2 LAST PATH I27
J 0
(-1725 4475);
DISPLAY 1.021277 (-1725 4475);
DISPLAY INVISIBLE (-1725 4475);
FORCEPROP 2 LAST CDS_LIB standard
J 2
(-1925 4400);
DISPLAY INVISIBLE (-1925 4400);
FORCEADD OFFPAGE..1
(-8150 4550);
FORCEPROP 2 LAST $XR5 192 
J 0
(-9032 4550);
DISPLAY 0.638298 (-9032 4550);
PAINT MONO (-9032 4550);
FORCEPROP 2 LAST $XR4 191 
J 0
(-8912 4550);
DISPLAY 0.638298 (-8912 4550);
PAINT MONO (-8912 4550);
FORCEPROP 2 LAST $XR3 189 
J 0
(-8792 4550);
DISPLAY 0.638298 (-8792 4550);
PAINT MONO (-8792 4550);
FORCEPROP 2 LAST $XR2 188 
J 0
(-8672 4550);
DISPLAY 0.638298 (-8672 4550);
PAINT MONO (-8672 4550);
FORCEPROP 2 LAST $XR1 187 
J 0
(-8552 4550);
DISPLAY 0.638298 (-8552 4550);
PAINT MONO (-8552 4550);
FORCEPROP 2 LAST $XR0 186 
J 0
(-8432 4550);
DISPLAY 0.638298 (-8432 4550);
PAINT MONO (-8432 4550);
FORCEPROP 2 LAST CDS_LIB standard
J 0
(-8150 4550);
DISPLAY INVISIBLE (-8150 4550);
FORCEPROP 1 LAST OFFPAGE TRUE
J 0
(-7825 4425);
DISPLAY 0.872340 (-7825 4425);
PAINT GREEN (-7825 4425);
DISPLAY INVISIBLE (-7825 4425);
FORCEPROP 1 LAST COMMENT_BODY TRUE
J 0
(-8025 4450);
DISPLAY 0.872340 (-8025 4450);
PAINT GREEN (-8025 4450);
DISPLAY INVISIBLE (-8025 4450);
FORCEPROP 2 LAST PATH I3
J 0
(-8100 4625);
DISPLAY 1.021277 (-8100 4625);
DISPLAY INVISIBLE (-8100 4625);
FORCEADD Q_CAP..1
(-1575 4475);
FORCEPROP 1 LAST LOCATION PC315_5
J 0
(-1525 4575);
DISPLAY 0.489362 (-1525 4575);
PAINT SKYBLUE (-1525 4575);
FORCEPROP 0 LAST $SEC 1
J 0
(-1525 4600);
DISPLAY 0.680851 (-1525 4600);
PAINT MONO (-1525 4600);
DISPLAY INVISIBLE (-1525 4600);
FORCEPROP 0 LAST CDS_SEC 1
J 0
(-1525 4600);
DISPLAY 1.021277 (-1525 4600);
DISPLAY INVISIBLE (-1525 4600);
FORCEPROP 1 LASTPIN (-1575 4575) $PN 1
J 0
(-1565 4555);
DISPLAY 0.489362 (-1565 4555);
PAINT MONO (-1565 4555);
FORCEPROP 1 LASTPIN (-1575 4375) $PN 2
J 0
(-1565 4355);
DISPLAY 0.489362 (-1565 4355);
PAINT MONO (-1565 4355);
FORCEPROP 1 LAST MATERIAL X6S
J 0
(-1525 4375);
DISPLAY 0.489362 (-1525 4375);
PAINT SKYBLUE (-1525 4375);
FORCEPROP 1 LAST TOLERANCE 20%
J 0
(-1525 4425);
DISPLAY 0.489362 (-1525 4425);
PAINT SKYBLUE (-1525 4425);
FORCEPROP 1 LAST VALUE 22UF
J 0
(-1525 4525);
DISPLAY 0.489362 (-1525 4525);
PAINT SKYBLUE (-1525 4525);
FORCEPROP 1 LAST PART_NUMBER TMP_QCH622KMEA01
J 0
(-1525 4325);
DISPLAY 0.489362 (-1525 4325);
PAINT SKYBLUE (-1525 4325);
FORCEPROP 1 LAST VOLTAGE 4V
J 0
(-1525 4475);
DISPLAY 0.489362 (-1525 4475);
PAINT SKYBLUE (-1525 4475);
FORCEPROP 1 LAST PACK_TYPE 0805
J 0
(-1525 4275);
DISPLAY 0.489362 (-1525 4275);
PAINT SKYBLUE (-1525 4275);
FORCEPROP 2 LAST CDS_LIB pure_quanta
J 0
(-1575 4475);
DISPLAY INVISIBLE (-1575 4475);
FORCEPROP 1 LAST PATH I30
J 0
(-1525 4625);
DISPLAY 0.978723 (-1525 4625);
PAINT WHITE (-1525 4625);
DISPLAY INVISIBLE (-1525 4625);
FORCEADD UNIVERSAL_GND..1
(-1150 4125);
FORCEPROP 3 LASTPIN (-1150 4175) SIG_NAME GND\g
J 0
(-1140 4185);
DISPLAY 0.659574 (-1140 4185);
PAINT MONO (-1140 4185);
DISPLAY INVISIBLE (-1140 4185);
FORCEPROP 2 LAST CDS_LIB pure_quanta_power
J 0
(-1150 4125);
DISPLAY INVISIBLE (-1150 4125);
FORCEPROP 1 LAST PATH I31
J 0
(-1075 4125);
DISPLAY 0.872340 (-1075 4125);
PAINT AQUA (-1075 4125);
DISPLAY INVISIBLE (-1075 4125);
FORCEPROP 1 LAST HDL_POWER GND
J 1
(-1125 4050);
DISPLAY 0.872340 (-1125 4050);
PAINT GREEN (-1125 4050);
DISPLAY INVISIBLE (-1125 4050);
FORCEADD Q_CAP..1
(-1150 4475);
FORCEPROP 1 LAST LOCATION PC316_5
J 0
(-1100 4575);
DISPLAY 0.489362 (-1100 4575);
PAINT SKYBLUE (-1100 4575);
FORCEPROP 0 LAST $SEC 1
J 0
(-1100 4600);
DISPLAY 0.680851 (-1100 4600);
PAINT MONO (-1100 4600);
DISPLAY INVISIBLE (-1100 4600);
FORCEPROP 0 LAST CDS_SEC 1
J 0
(-1100 4600);
DISPLAY 1.021277 (-1100 4600);
DISPLAY INVISIBLE (-1100 4600);
FORCEPROP 1 LASTPIN (-1150 4575) $PN 1
J 0
(-1140 4555);
DISPLAY 0.489362 (-1140 4555);
PAINT MONO (-1140 4555);
FORCEPROP 1 LASTPIN (-1150 4375) $PN 2
J 0
(-1140 4355);
DISPLAY 0.489362 (-1140 4355);
PAINT MONO (-1140 4355);
FORCEPROP 1 LAST MATERIAL X6S
J 0
(-1100 4375);
DISPLAY 0.489362 (-1100 4375);
PAINT SKYBLUE (-1100 4375);
FORCEPROP 1 LAST TOLERANCE 20%
J 0
(-1100 4425);
DISPLAY 0.489362 (-1100 4425);
PAINT SKYBLUE (-1100 4425);
FORCEPROP 1 LAST VALUE 22UF
J 0
(-1100 4525);
DISPLAY 0.489362 (-1100 4525);
PAINT SKYBLUE (-1100 4525);
FORCEPROP 1 LAST PART_NUMBER TMP_QCH622KMEA01
J 0
(-1100 4325);
DISPLAY 0.489362 (-1100 4325);
PAINT SKYBLUE (-1100 4325);
FORCEPROP 1 LAST VOLTAGE 4V
J 0
(-1100 4475);
DISPLAY 0.489362 (-1100 4475);
PAINT SKYBLUE (-1100 4475);
FORCEPROP 1 LAST PACK_TYPE 0805
J 0
(-1100 4275);
DISPLAY 0.489362 (-1100 4275);
PAINT SKYBLUE (-1100 4275);
FORCEPROP 2 LAST CDS_LIB pure_quanta
J 0
(-1150 4475);
DISPLAY INVISIBLE (-1150 4475);
FORCEPROP 1 LAST PATH I32
J 0
(-1100 4625);
DISPLAY 0.978723 (-1100 4625);
PAINT WHITE (-1100 4625);
DISPLAY INVISIBLE (-1100 4625);
FORCEADD VCC_CORE..1
(-1150 4800);
FORCEPROP 3 LASTPIN (-1150 4750) SIG_NAME PVDDCR_CPU0_P1\g
J 0
(-1140 4760);
DISPLAY 0.659574 (-1140 4760);
PAINT MONO (-1140 4760);
DISPLAY INVISIBLE (-1140 4760);
FORCEPROP 1 LAST HDL_POWER PVDDCR_CPU0_P1
J 1
(-1150 4850);
DISPLAY 0.489362 (-1150 4850);
PAINT GREEN (-1150 4850);
FORCEPROP 2 LAST CDS_LIB pure_quanta_power
J 0
(-1150 4800);
DISPLAY INVISIBLE (-1150 4800);
FORCEPROP 1 LAST PATH I33
J 0
(-1100 4825);
DISPLAY 0.872340 (-1100 4825);
PAINT AQUA (-1100 4825);
DISPLAY INVISIBLE (-1100 4825);
FORCEADD OFFPAGE..3
R 2
(-3775 4400);
FORCEPROP 2 LAST $XR0 189 
J 0
(-4085 4400);
DISPLAY 0.638298 (-4085 4400);
PAINT MONO (-4085 4400);
FORCEPROP 2 LAST CDS_LIB standard
J 2
(-3775 4400);
DISPLAY INVISIBLE (-3775 4400);
FORCEPROP 1 LAST OFFPAGE TRUE
J 2
(-4100 4275);
DISPLAY 0.872340 (-4100 4275);
PAINT GREEN (-4100 4275);
DISPLAY INVISIBLE (-4100 4275);
FORCEPROP 1 LAST COMMENT_BODY TRUE
J 2
(-3725 4300);
DISPLAY 0.872340 (-3725 4300);
PAINT GREEN (-3725 4300);
DISPLAY INVISIBLE (-3725 4300);
FORCEPROP 2 LAST PATH I34
J 0
(-3725 4475);
DISPLAY 1.021277 (-3725 4475);
DISPLAY INVISIBLE (-3725 4475);
FORCEADD ISL99390FRZTR5935..1
(-6100 4650);
FORCEPROP 1 LAST LOCATION PU29
J 0
(-6400 5525);
DISPLAY 0.489362 (-6400 5525);
PAINT SKYBLUE (-6400 5525);
FORCEPROP 0 LAST $SEC 1
J 0
(-6400 5675);
DISPLAY 0.680851 (-6400 5675);
PAINT MONO (-6400 5675);
DISPLAY INVISIBLE (-6400 5675);
FORCEPROP 2 LAST CDS_SEC 1
J 0
(-6400 5675);
DISPLAY 1.021277 (-6400 5675);
DISPLAY INVISIBLE (-6400 5675);
FORCEPROP 0 LASTPIN (-5700 4200) $PN 2
J 0
(-5690 4210);
DISPLAY 0.489362 (-5690 4210);
PAINT MONO (-5690 4210);
FORCEPROP 0 LASTPIN (-5700 5000) $PN 33
J 0
(-5690 5010);
DISPLAY 0.489362 (-5690 5010);
PAINT MONO (-5690 5010);
FORCEPROP 0 LASTPIN (-6550 4400) $PN 31
J 2
(-6560 4410);
DISPLAY 0.489362 (-6560 4410);
PAINT MONO (-6560 4410);
FORCEPROP 0 LASTPIN (-6550 4800) $PN 35
J 2
(-6560 4810);
DISPLAY 0.489362 (-6560 4810);
PAINT MONO (-6560 4810);
FORCEPROP 0 LASTPIN (-5700 4350) $PN 6
J 0
(-5690 4360);
DISPLAY 0.489362 (-5690 4360);
PAINT MONO (-5690 4360);
FORCEPROP 0 LASTPIN (-5700 4300) $PN 41
J 0
(-5690 4310);
DISPLAY 0.489362 (-5690 4310);
PAINT MONO (-5690 4310);
FORCEPROP 0 LASTPIN (-6550 4650) $PN 38
J 2
(-6560 4660);
DISPLAY 0.489362 (-6560 4660);
PAINT MONO (-6560 4660);
FORCEPROP 0 LASTPIN (-6550 4350) $PN 37
J 2
(-6560 4360);
DISPLAY 0.489362 (-6560 4360);
PAINT MONO (-6560 4360);
FORCEPROP 0 LASTPIN (-5700 4150) $PN 5
J 0
(-5690 4160);
DISPLAY 0.489362 (-5690 4160);
PAINT MONO (-5690 4160);
FORCEPROP 0 LASTPIN (-5700 4100) $PN 7_9-20_24
J 0
(-5690 4110);
DISPLAY 0.489362 (-5690 4110);
PAINT MONO (-5690 4110);
FORCEPROP 0 LASTPIN (-5700 4050) $PN 40
J 0
(-5690 4060);
DISPLAY 0.489362 (-5690 4060);
PAINT MONO (-5690 4060);
FORCEPROP 0 LASTPIN (-5700 4750) $PN 32
J 0
(-5690 4760);
DISPLAY 0.489362 (-5690 4760);
PAINT MONO (-5690 4760);
FORCEPROP 0 LASTPIN (-6550 5300) $PN 4
J 2
(-6560 5310);
DISPLAY 0.489362 (-6560 5310);
PAINT MONO (-6560 5310);
FORCEPROP 0 LASTPIN (-6550 4050) $PN 34
J 2
(-6560 4060);
DISPLAY 0.489362 (-6560 4060);
PAINT MONO (-6560 4060);
FORCEPROP 0 LASTPIN (-6550 4550) $PN 39
J 2
(-6560 4560);
DISPLAY 0.489362 (-6560 4560);
PAINT MONO (-6560 4560);
FORCEPROP 0 LASTPIN (-5700 4650) $PN 10_19
J 0
(-5690 4660);
DISPLAY 0.489362 (-5690 4660);
PAINT MONO (-5690 4660);
FORCEPROP 0 LASTPIN (-6550 4150) $PN 36
J 2
(-6560 4160);
DISPLAY 0.489362 (-6560 4160);
PAINT MONO (-6560 4160);
FORCEPROP 0 LASTPIN (-6550 5000) $PN 3
J 2
(-6560 5010);
DISPLAY 0.489362 (-6560 5010);
PAINT MONO (-6560 5010);
FORCEPROP 0 LASTPIN (-5700 5300) $PN 25_29
J 0
(-5690 5310);
DISPLAY 0.489362 (-5690 5310);
PAINT MONO (-5690 5310);
FORCEPROP 0 LASTPIN (-5700 5250) $PN 30
J 0
(-5690 5260);
DISPLAY 0.489362 (-5690 5260);
PAINT MONO (-5690 5260);
FORCEPROP 0 LASTPIN (-5700 4400) $PN 1
J 0
(-5690 4410);
DISPLAY 0.489362 (-5690 4410);
PAINT MONO (-5690 4410);
FORCEPROP 2 LAST PART_TYPE SMLF
J 0
(-6400 5625);
DISPLAY 1.021277 (-6400 5625);
FORCEPROP 1 LAST MATERIAL IC
J 0
(-6400 5375);
DISPLAY 0.489362 (-6400 5375);
PAINT SKYBLUE (-6400 5375);
FORCEPROP 2 LAST VALUE ISL99390FRZ-TR5935
J 0
(-6400 5575);
DISPLAY 0.489362 (-6400 5575);
PAINT SKYBLUE (-6400 5575);
FORCEPROP 1 LAST PART_NUMBER AL099390004
J 0
(-6400 5450);
DISPLAY 0.489362 (-6400 5450);
PAINT SKYBLUE (-6400 5450);
FORCEPROP 2 LAST CDS_LIB pure_quanta
J 0
(-6100 4650);
DISPLAY INVISIBLE (-6100 4650);
FORCEPROP 1 LAST NEEDS_NO_SIZE TRUE
J 0
(-6100 4650);
DISPLAY 0.723404 (-6100 4650);
PAINT GREEN (-6100 4650);
DISPLAY INVISIBLE (-6100 4650);
FORCEPROP 1 LAST CDS_LMAN_SYM_OUTLINE -300,700,250,-650
J 0
(-6100 4650);
DISPLAY 0.468085 (-6100 4650);
PAINT GREEN (-6100 4650);
DISPLAY INVISIBLE (-6100 4650);
FORCEPROP 1 LAST PATH I35
J 0
(-6100 4650);
DISPLAY 0.723404 (-6100 4650);
PAINT GREEN (-6100 4650);
DISPLAY INVISIBLE (-6100 4650);
FORCEADD Q_CAP..1
(-5350 5525);
FORCEPROP 1 LAST LOCATION PC309_5
J 0
(-5300 5625);
DISPLAY 0.489362 (-5300 5625);
PAINT SKYBLUE (-5300 5625);
FORCEPROP 0 LAST $SEC 1
J 0
(-5300 5675);
DISPLAY 0.680851 (-5300 5675);
PAINT MONO (-5300 5675);
DISPLAY INVISIBLE (-5300 5675);
FORCEPROP 0 LAST CDS_SEC 1
J 0
(-5300 5675);
DISPLAY 1.021277 (-5300 5675);
DISPLAY INVISIBLE (-5300 5675);
FORCEPROP 1 LASTPIN (-5350 5625) $PN 1
J 0
(-5340 5605);
DISPLAY 0.489362 (-5340 5605);
PAINT MONO (-5340 5605);
FORCEPROP 1 LASTPIN (-5350 5425) $PN 2
J 0
(-5340 5405);
DISPLAY 0.489362 (-5340 5405);
PAINT MONO (-5340 5405);
FORCEPROP 1 LAST MATERIAL X7R
J 0
(-5300 5425);
DISPLAY 0.489362 (-5300 5425);
PAINT SKYBLUE (-5300 5425);
FORCEPROP 1 LAST TOLERANCE 10%
J 0
(-5300 5475);
DISPLAY 0.489362 (-5300 5475);
PAINT SKYBLUE (-5300 5475);
FORCEPROP 1 LAST VALUE 0.1UF
J 0
(-5300 5575);
DISPLAY 0.489362 (-5300 5575);
PAINT SKYBLUE (-5300 5575);
FORCEPROP 1 LAST PART_NUMBER CH4104K1B00
J 0
(-5300 5375);
DISPLAY 0.489362 (-5300 5375);
PAINT SKYBLUE (-5300 5375);
FORCEPROP 1 LAST VOLTAGE 25V
J 0
(-5300 5525);
DISPLAY 0.489362 (-5300 5525);
PAINT SKYBLUE (-5300 5525);
FORCEPROP 1 LAST PACK_TYPE 0402
J 0
(-5300 5325);
DISPLAY 0.489362 (-5300 5325);
PAINT SKYBLUE (-5300 5325);
FORCEPROP 2 LAST CDS_LIB pure_quanta
J 0
(-5350 5525);
DISPLAY INVISIBLE (-5350 5525);
FORCEPROP 1 LAST PATH I36
J 0
(-5300 5675);
DISPLAY 0.978723 (-5300 5675);
PAINT WHITE (-5300 5675);
DISPLAY INVISIBLE (-5300 5675);
FORCEADD Q_CAP..1
(-7600 5000);
FORCEPROP 1 LAST LOCATION PC307
J 0
(-7550 5100);
DISPLAY 0.489362 (-7550 5100);
PAINT SKYBLUE (-7550 5100);
FORCEPROP 0 LAST $SEC 1
J 0
(-7550 5150);
DISPLAY 0.680851 (-7550 5150);
PAINT MONO (-7550 5150);
DISPLAY INVISIBLE (-7550 5150);
FORCEPROP 0 LAST CDS_SEC 1
J 0
(-7550 5150);
DISPLAY 1.021277 (-7550 5150);
DISPLAY INVISIBLE (-7550 5150);
FORCEPROP 1 LASTPIN (-7600 5100) $PN 1
J 0
(-7590 5080);
DISPLAY 0.489362 (-7590 5080);
PAINT MONO (-7590 5080);
FORCEPROP 1 LASTPIN (-7600 4900) $PN 2
J 0
(-7590 4880);
DISPLAY 0.489362 (-7590 4880);
PAINT MONO (-7590 4880);
FORCEPROP 1 LAST MATERIAL X6S
J 0
(-7550 4900);
DISPLAY 0.489362 (-7550 4900);
PAINT SKYBLUE (-7550 4900);
FORCEPROP 1 LAST TOLERANCE 10%
J 0
(-7550 4950);
DISPLAY 0.489362 (-7550 4950);
PAINT SKYBLUE (-7550 4950);
FORCEPROP 1 LAST VALUE 2.2UF
J 0
(-7550 5050);
DISPLAY 0.489362 (-7550 5050);
PAINT SKYBLUE (-7550 5050);
FORCEPROP 1 LAST PART_NUMBER CH5222KEB01
J 0
(-7550 4850);
DISPLAY 0.489362 (-7550 4850);
PAINT SKYBLUE (-7550 4850);
FORCEPROP 1 LAST VOLTAGE 10V
J 0
(-7550 5000);
DISPLAY 0.489362 (-7550 5000);
PAINT SKYBLUE (-7550 5000);
FORCEPROP 1 LAST PACK_TYPE C0402
J 0
(-7550 4800);
DISPLAY 0.489362 (-7550 4800);
PAINT SKYBLUE (-7550 4800);
FORCEPROP 2 LAST CDS_LIB pure_quanta
J 0
(-7600 5000);
DISPLAY INVISIBLE (-7600 5000);
FORCEPROP 1 LAST PATH I37
J 0
(-7550 5150);
DISPLAY 0.978723 (-7550 5150);
PAINT WHITE (-7550 5150);
DISPLAY INVISIBLE (-7550 5150);
FORCEADD UNIVERSAL_GND..1
(-7600 4800);
FORCEPROP 3 LASTPIN (-7600 4850) SIG_NAME GND\g
J 0
(-7590 4860);
DISPLAY 0.659574 (-7590 4860);
PAINT MONO (-7590 4860);
DISPLAY INVISIBLE (-7590 4860);
FORCEPROP 2 LAST CDS_LIB pure_quanta_power
J 0
(-7600 4800);
DISPLAY INVISIBLE (-7600 4800);
FORCEPROP 1 LAST PATH I38
J 0
(-7525 4800);
DISPLAY 0.872340 (-7525 4800);
PAINT AQUA (-7525 4800);
DISPLAY INVISIBLE (-7525 4800);
FORCEPROP 1 LAST HDL_POWER GND
J 1
(-7575 4725);
DISPLAY 0.872340 (-7575 4725);
PAINT GREEN (-7575 4725);
DISPLAY INVISIBLE (-7575 4725);
FORCEADD UNIVERSAL_GND..1
(-7250 5300);
FORCEPROP 3 LASTPIN (-7250 5350) SIG_NAME GND\g
J 0
(-7240 5360);
DISPLAY 0.659574 (-7240 5360);
PAINT MONO (-7240 5360);
DISPLAY INVISIBLE (-7240 5360);
FORCEPROP 2 LAST CDS_LIB pure_quanta_power
J 0
(-7250 5300);
DISPLAY INVISIBLE (-7250 5300);
FORCEPROP 1 LAST PATH I39
J 0
(-7175 5300);
DISPLAY 0.872340 (-7175 5300);
PAINT AQUA (-7175 5300);
DISPLAY INVISIBLE (-7175 5300);
FORCEPROP 1 LAST HDL_POWER GND
J 1
(-7225 5225);
DISPLAY 0.872340 (-7225 5225);
PAINT GREEN (-7225 5225);
DISPLAY INVISIBLE (-7225 5225);
FORCEADD OFFPAGE..1
(-7200 4050);
FORCEPROP 2 LAST $XR0 186 
J 0
(-7452 4050);
DISPLAY 0.638298 (-7452 4050);
PAINT MONO (-7452 4050);
FORCEPROP 2 LAST CDS_LIB standard
J 2
(-7200 4050);
DISPLAY INVISIBLE (-7200 4050);
FORCEPROP 1 LAST OFFPAGE TRUE
J 0
(-6875 3925);
DISPLAY 0.872340 (-6875 3925);
PAINT GREEN (-6875 3925);
DISPLAY INVISIBLE (-6875 3925);
FORCEPROP 1 LAST COMMENT_BODY TRUE
J 0
(-7075 3950);
DISPLAY 0.872340 (-7075 3950);
PAINT GREEN (-7075 3950);
DISPLAY INVISIBLE (-7075 3950);
FORCEPROP 2 LAST PATH I4
J 0
(-7150 4125);
DISPLAY 1.021277 (-7150 4125);
DISPLAY INVISIBLE (-7150 4125);
FORCEADD Q_RES..2
(-7600 5550);
FORCEPROP 1 LAST LOCATION PR201
J 0
(-7555 5675);
DISPLAY 0.489362 (-7555 5675);
PAINT SKYBLUE (-7555 5675);
FORCEPROP 0 LAST $SEC 1
J 0
(-7550 5725);
DISPLAY 0.680851 (-7550 5725);
PAINT MONO (-7550 5725);
DISPLAY INVISIBLE (-7550 5725);
FORCEPROP 0 LAST CDS_SEC 1
J 0
(-7550 5725);
DISPLAY 1.021277 (-7550 5725);
DISPLAY INVISIBLE (-7550 5725);
FORCEPROP 1 LASTPIN (-7600 5650) $PN 1
J 0
(-7595 5612);
DISPLAY 0.489362 (-7595 5612);
PAINT MONO (-7595 5612);
FORCEPROP 1 LASTPIN (-7600 5450) $PN 2
J 0
(-7595 5460);
DISPLAY 0.489362 (-7595 5460);
PAINT MONO (-7595 5460);
FORCEPROP 1 LAST WATTAGE 1/16W
J 0
(-7550 5525);
DISPLAY 0.489362 (-7550 5525);
PAINT SKYBLUE (-7550 5525);
FORCEPROP 1 LAST MATERIAL CHIP
J 0
(-7550 5475);
DISPLAY 0.489362 (-7550 5475);
PAINT SKYBLUE (-7550 5475);
FORCEPROP 1 LAST TOLERANCE 1%
J 0
(-7550 5575);
DISPLAY 0.489362 (-7550 5575);
PAINT SKYBLUE (-7550 5575);
FORCEPROP 1 LAST VALUE 2.2
J 0
(-7550 5625);
DISPLAY 0.489362 (-7550 5625);
PAINT SKYBLUE (-7550 5625);
FORCEPROP 1 LAST PART_NUMBER CS-2202FB00
J 0
(-7550 5425);
DISPLAY 0.489362 (-7550 5425);
PAINT SKYBLUE (-7550 5425);
FORCEPROP 1 LAST PACK_TYPE 0402LF
J 0
(-7550 5375);
DISPLAY 0.489362 (-7550 5375);
PAINT SKYBLUE (-7550 5375);
FORCEPROP 2 LAST CDS_LIB pure_quanta
J 0
(-7600 5550);
DISPLAY INVISIBLE (-7600 5550);
FORCEPROP 1 LAST PATH I40
J 0
(-7550 5725);
DISPLAY 0.978723 (-7550 5725);
PAINT WHITE (-7550 5725);
DISPLAY INVISIBLE (-7550 5725);
FORCEADD Q_CAP..1
(-7250 5575);
FORCEPROP 1 LAST LOCATION PC308_C0P1_5
J 0
(-7200 5675);
DISPLAY 0.489362 (-7200 5675);
PAINT SKYBLUE (-7200 5675);
FORCEPROP 0 LAST $SEC 1
J 0
(-7200 5725);
DISPLAY 0.680851 (-7200 5725);
PAINT MONO (-7200 5725);
DISPLAY INVISIBLE (-7200 5725);
FORCEPROP 0 LAST CDS_SEC 1
J 0
(-7200 5725);
DISPLAY 1.021277 (-7200 5725);
DISPLAY INVISIBLE (-7200 5725);
FORCEPROP 1 LASTPIN (-7250 5675) $PN 1
J 0
(-7240 5655);
DISPLAY 0.489362 (-7240 5655);
PAINT MONO (-7240 5655);
FORCEPROP 1 LASTPIN (-7250 5475) $PN 2
J 0
(-7240 5455);
DISPLAY 0.489362 (-7240 5455);
PAINT MONO (-7240 5455);
FORCEPROP 1 LAST MATERIAL X6S
J 0
(-7200 5475);
DISPLAY 0.489362 (-7200 5475);
PAINT SKYBLUE (-7200 5475);
FORCEPROP 1 LAST TOLERANCE 10%
J 0
(-7200 5525);
DISPLAY 0.489362 (-7200 5525);
PAINT SKYBLUE (-7200 5525);
FORCEPROP 1 LAST VALUE 2.2UF
J 0
(-7200 5625);
DISPLAY 0.489362 (-7200 5625);
PAINT SKYBLUE (-7200 5625);
FORCEPROP 1 LAST PART_NUMBER CH5222KEB01
J 0
(-7200 5425);
DISPLAY 0.489362 (-7200 5425);
PAINT SKYBLUE (-7200 5425);
FORCEPROP 1 LAST VOLTAGE 10V
J 0
(-7200 5575);
DISPLAY 0.489362 (-7200 5575);
PAINT SKYBLUE (-7200 5575);
FORCEPROP 1 LAST PACK_TYPE C0402
J 0
(-7200 5375);
DISPLAY 0.489362 (-7200 5375);
PAINT SKYBLUE (-7200 5375);
FORCEPROP 2 LAST CDS_LIB pure_quanta
J 0
(-7250 5575);
DISPLAY INVISIBLE (-7250 5575);
FORCEPROP 1 LAST PATH I41
J 0
(-7200 5725);
DISPLAY 0.978723 (-7200 5725);
PAINT WHITE (-7200 5725);
DISPLAY INVISIBLE (-7200 5725);
FORCEADD VCC_CORE..1
(-7600 5950);
FORCEPROP 3 LASTPIN (-7600 5900) SIG_NAME PVDDCR_CPU0_P1_PVCC\g
J 0
(-7590 5910);
DISPLAY 0.659574 (-7590 5910);
PAINT MONO (-7590 5910);
DISPLAY INVISIBLE (-7590 5910);
FORCEPROP 1 LAST HDL_POWER PVDDCR_CPU0_P1_PVCC
J 1
(-7600 6000);
DISPLAY 0.489362 (-7600 6000);
PAINT GREEN (-7600 6000);
FORCEPROP 2 LAST CDS_LIB pure_quanta_power
J 0
(-7600 5950);
DISPLAY INVISIBLE (-7600 5950);
FORCEPROP 1 LAST PATH I42
J 0
(-7550 5975);
DISPLAY 0.872340 (-7550 5975);
PAINT AQUA (-7550 5975);
DISPLAY INVISIBLE (-7550 5975);
FORCEADD ISL99390FRZTR5935..1
(-6050 1750);
FORCEPROP 1 LAST LOCATION PU24
J 0
(-6350 2625);
DISPLAY 0.489362 (-6350 2625);
PAINT SKYBLUE (-6350 2625);
FORCEPROP 0 LAST $SEC 1
J 0
(-6350 2775);
DISPLAY 0.680851 (-6350 2775);
PAINT MONO (-6350 2775);
DISPLAY INVISIBLE (-6350 2775);
FORCEPROP 2 LAST CDS_SEC 1
J 0
(-6350 2775);
DISPLAY 1.021277 (-6350 2775);
DISPLAY INVISIBLE (-6350 2775);
FORCEPROP 0 LASTPIN (-5650 1300) $PN 2
J 0
(-5640 1310);
DISPLAY 0.489362 (-5640 1310);
PAINT MONO (-5640 1310);
FORCEPROP 0 LASTPIN (-5650 2100) $PN 33
J 0
(-5640 2110);
DISPLAY 0.489362 (-5640 2110);
PAINT MONO (-5640 2110);
FORCEPROP 0 LASTPIN (-6500 1500) $PN 31
J 2
(-6510 1510);
DISPLAY 0.489362 (-6510 1510);
PAINT MONO (-6510 1510);
FORCEPROP 0 LASTPIN (-6500 1900) $PN 35
J 2
(-6510 1910);
DISPLAY 0.489362 (-6510 1910);
PAINT MONO (-6510 1910);
FORCEPROP 0 LASTPIN (-5650 1450) $PN 6
J 0
(-5640 1460);
DISPLAY 0.489362 (-5640 1460);
PAINT MONO (-5640 1460);
FORCEPROP 0 LASTPIN (-5650 1400) $PN 41
J 0
(-5640 1410);
DISPLAY 0.489362 (-5640 1410);
PAINT MONO (-5640 1410);
FORCEPROP 0 LASTPIN (-6500 1750) $PN 38
J 2
(-6510 1760);
DISPLAY 0.489362 (-6510 1760);
PAINT MONO (-6510 1760);
FORCEPROP 0 LASTPIN (-6500 1450) $PN 37
J 2
(-6510 1460);
DISPLAY 0.489362 (-6510 1460);
PAINT MONO (-6510 1460);
FORCEPROP 0 LASTPIN (-5650 1250) $PN 5
J 0
(-5640 1260);
DISPLAY 0.489362 (-5640 1260);
PAINT MONO (-5640 1260);
FORCEPROP 0 LASTPIN (-5650 1200) $PN 7_9-20_24
J 0
(-5640 1210);
DISPLAY 0.489362 (-5640 1210);
PAINT MONO (-5640 1210);
FORCEPROP 0 LASTPIN (-5650 1150) $PN 40
J 0
(-5640 1160);
DISPLAY 0.489362 (-5640 1160);
PAINT MONO (-5640 1160);
FORCEPROP 0 LASTPIN (-5650 1850) $PN 32
J 0
(-5640 1860);
DISPLAY 0.489362 (-5640 1860);
PAINT MONO (-5640 1860);
FORCEPROP 0 LASTPIN (-6500 2400) $PN 4
J 2
(-6510 2410);
DISPLAY 0.489362 (-6510 2410);
PAINT MONO (-6510 2410);
FORCEPROP 0 LASTPIN (-6500 1150) $PN 34
J 2
(-6510 1160);
DISPLAY 0.489362 (-6510 1160);
PAINT MONO (-6510 1160);
FORCEPROP 0 LASTPIN (-6500 1650) $PN 39
J 2
(-6510 1660);
DISPLAY 0.489362 (-6510 1660);
PAINT MONO (-6510 1660);
FORCEPROP 0 LASTPIN (-5650 1750) $PN 10_19
J 0
(-5640 1760);
DISPLAY 0.489362 (-5640 1760);
PAINT MONO (-5640 1760);
FORCEPROP 0 LASTPIN (-6500 1250) $PN 36
J 2
(-6510 1260);
DISPLAY 0.489362 (-6510 1260);
PAINT MONO (-6510 1260);
FORCEPROP 0 LASTPIN (-6500 2100) $PN 3
J 2
(-6510 2110);
DISPLAY 0.489362 (-6510 2110);
PAINT MONO (-6510 2110);
FORCEPROP 0 LASTPIN (-5650 2400) $PN 25_29
J 0
(-5640 2410);
DISPLAY 0.489362 (-5640 2410);
PAINT MONO (-5640 2410);
FORCEPROP 0 LASTPIN (-5650 2350) $PN 30
J 0
(-5640 2360);
DISPLAY 0.489362 (-5640 2360);
PAINT MONO (-5640 2360);
FORCEPROP 0 LASTPIN (-5650 1500) $PN 1
J 0
(-5640 1510);
DISPLAY 0.489362 (-5640 1510);
PAINT MONO (-5640 1510);
FORCEPROP 2 LAST PART_TYPE SMLF
J 0
(-6350 2725);
DISPLAY 1.021277 (-6350 2725);
FORCEPROP 1 LAST MATERIAL IC
J 0
(-6350 2475);
DISPLAY 0.489362 (-6350 2475);
PAINT SKYBLUE (-6350 2475);
FORCEPROP 2 LAST VALUE ISL99390FRZ-TR5935
J 0
(-6350 2675);
DISPLAY 0.489362 (-6350 2675);
PAINT SKYBLUE (-6350 2675);
FORCEPROP 1 LAST PART_NUMBER AL099390004
J 0
(-6350 2550);
DISPLAY 0.489362 (-6350 2550);
PAINT SKYBLUE (-6350 2550);
FORCEPROP 2 LAST CDS_LIB pure_quanta
J 0
(-6050 1750);
DISPLAY INVISIBLE (-6050 1750);
FORCEPROP 1 LAST NEEDS_NO_SIZE TRUE
J 0
(-6050 1750);
DISPLAY 0.723404 (-6050 1750);
PAINT GREEN (-6050 1750);
DISPLAY INVISIBLE (-6050 1750);
FORCEPROP 1 LAST CDS_LMAN_SYM_OUTLINE -300,700,250,-650
J 0
(-6050 1750);
DISPLAY 0.468085 (-6050 1750);
PAINT GREEN (-6050 1750);
DISPLAY INVISIBLE (-6050 1750);
FORCEPROP 1 LAST PATH I43
J 0
(-6050 1750);
DISPLAY 0.723404 (-6050 1750);
PAINT GREEN (-6050 1750);
DISPLAY INVISIBLE (-6050 1750);
FORCEADD VCC_CORE..1
(-1100 1900);
FORCEPROP 3 LASTPIN (-1100 1850) SIG_NAME PVDDCR_CPU0_P1\g
J 0
(-1090 1860);
DISPLAY 0.659574 (-1090 1860);
PAINT MONO (-1090 1860);
DISPLAY INVISIBLE (-1090 1860);
FORCEPROP 1 LAST HDL_POWER PVDDCR_CPU0_P1
J 1
(-1100 1950);
DISPLAY 0.489362 (-1100 1950);
PAINT GREEN (-1100 1950);
FORCEPROP 2 LAST CDS_LIB pure_quanta_power
J 0
(-1100 1900);
DISPLAY INVISIBLE (-1100 1900);
FORCEPROP 1 LAST PATH I44
J 0
(-1050 1925);
DISPLAY 0.872340 (-1050 1925);
PAINT AQUA (-1050 1925);
DISPLAY INVISIBLE (-1050 1925);
FORCEADD Q_CAP..1
(-1100 1575);
FORCEPROP 1 LAST LOCATION PC135_6
J 0
(-1050 1675);
DISPLAY 0.489362 (-1050 1675);
PAINT SKYBLUE (-1050 1675);
FORCEPROP 0 LAST $SEC 1
J 0
(-1050 1700);
DISPLAY 0.680851 (-1050 1700);
PAINT MONO (-1050 1700);
DISPLAY INVISIBLE (-1050 1700);
FORCEPROP 0 LAST CDS_SEC 1
J 0
(-1050 1700);
DISPLAY 1.021277 (-1050 1700);
DISPLAY INVISIBLE (-1050 1700);
FORCEPROP 1 LASTPIN (-1100 1675) $PN 1
J 0
(-1090 1655);
DISPLAY 0.489362 (-1090 1655);
PAINT MONO (-1090 1655);
FORCEPROP 1 LASTPIN (-1100 1475) $PN 2
J 0
(-1090 1455);
DISPLAY 0.489362 (-1090 1455);
PAINT MONO (-1090 1455);
FORCEPROP 1 LAST MATERIAL X6S
J 0
(-1050 1475);
DISPLAY 0.489362 (-1050 1475);
PAINT SKYBLUE (-1050 1475);
FORCEPROP 1 LAST TOLERANCE 20%
J 0
(-1050 1525);
DISPLAY 0.489362 (-1050 1525);
PAINT SKYBLUE (-1050 1525);
FORCEPROP 1 LAST VALUE 22UF
J 0
(-1050 1625);
DISPLAY 0.489362 (-1050 1625);
PAINT SKYBLUE (-1050 1625);
FORCEPROP 1 LAST PART_NUMBER TMP_QCH622KMEA01
J 0
(-1050 1425);
DISPLAY 0.489362 (-1050 1425);
PAINT SKYBLUE (-1050 1425);
FORCEPROP 1 LAST VOLTAGE 4V
J 0
(-1050 1575);
DISPLAY 0.489362 (-1050 1575);
PAINT SKYBLUE (-1050 1575);
FORCEPROP 1 LAST PACK_TYPE 0805
J 0
(-1050 1375);
DISPLAY 0.489362 (-1050 1375);
PAINT SKYBLUE (-1050 1375);
FORCEPROP 2 LAST CDS_LIB pure_quanta
J 0
(-1100 1575);
DISPLAY INVISIBLE (-1100 1575);
FORCEPROP 1 LAST PATH I45
J 0
(-1050 1725);
DISPLAY 0.978723 (-1050 1725);
PAINT WHITE (-1050 1725);
DISPLAY INVISIBLE (-1050 1725);
FORCEADD UNIVERSAL_GND..1
(-1100 1225);
FORCEPROP 3 LASTPIN (-1100 1275) SIG_NAME GND\g
J 0
(-1090 1285);
DISPLAY 0.659574 (-1090 1285);
PAINT MONO (-1090 1285);
DISPLAY INVISIBLE (-1090 1285);
FORCEPROP 2 LAST CDS_LIB pure_quanta_power
J 0
(-1100 1225);
DISPLAY INVISIBLE (-1100 1225);
FORCEPROP 1 LAST PATH I46
J 0
(-1025 1225);
DISPLAY 0.872340 (-1025 1225);
PAINT AQUA (-1025 1225);
DISPLAY INVISIBLE (-1025 1225);
FORCEPROP 1 LAST HDL_POWER GND
J 1
(-1075 1150);
DISPLAY 0.872340 (-1075 1150);
PAINT GREEN (-1075 1150);
DISPLAY INVISIBLE (-1075 1150);
FORCEADD Q_CAP..1
(-1525 1575);
FORCEPROP 1 LAST LOCATION PC134_6
J 0
(-1475 1675);
DISPLAY 0.489362 (-1475 1675);
PAINT SKYBLUE (-1475 1675);
FORCEPROP 0 LAST $SEC 1
J 0
(-1475 1700);
DISPLAY 0.680851 (-1475 1700);
PAINT MONO (-1475 1700);
DISPLAY INVISIBLE (-1475 1700);
FORCEPROP 0 LAST CDS_SEC 1
J 0
(-1475 1700);
DISPLAY 1.021277 (-1475 1700);
DISPLAY INVISIBLE (-1475 1700);
FORCEPROP 1 LASTPIN (-1525 1675) $PN 1
J 0
(-1515 1655);
DISPLAY 0.489362 (-1515 1655);
PAINT MONO (-1515 1655);
FORCEPROP 1 LASTPIN (-1525 1475) $PN 2
J 0
(-1515 1455);
DISPLAY 0.489362 (-1515 1455);
PAINT MONO (-1515 1455);
FORCEPROP 1 LAST MATERIAL X6S
J 0
(-1475 1475);
DISPLAY 0.489362 (-1475 1475);
PAINT SKYBLUE (-1475 1475);
FORCEPROP 1 LAST TOLERANCE 20%
J 0
(-1475 1525);
DISPLAY 0.489362 (-1475 1525);
PAINT SKYBLUE (-1475 1525);
FORCEPROP 1 LAST VALUE 22UF
J 0
(-1475 1625);
DISPLAY 0.489362 (-1475 1625);
PAINT SKYBLUE (-1475 1625);
FORCEPROP 1 LAST PART_NUMBER TMP_QCH622KMEA01
J 0
(-1475 1425);
DISPLAY 0.489362 (-1475 1425);
PAINT SKYBLUE (-1475 1425);
FORCEPROP 1 LAST VOLTAGE 4V
J 0
(-1475 1575);
DISPLAY 0.489362 (-1475 1575);
PAINT SKYBLUE (-1475 1575);
FORCEPROP 1 LAST PACK_TYPE 0805
J 0
(-1475 1375);
DISPLAY 0.489362 (-1475 1375);
PAINT SKYBLUE (-1475 1375);
FORCEPROP 2 LAST CDS_LIB pure_quanta
J 0
(-1525 1575);
DISPLAY INVISIBLE (-1525 1575);
FORCEPROP 1 LAST PATH I47
J 0
(-1475 1725);
DISPLAY 0.978723 (-1475 1725);
PAINT WHITE (-1475 1725);
DISPLAY INVISIBLE (-1475 1725);
FORCEADD OFFPAGE..3
(-1875 1500);
FORCEPROP 2 LAST $XR0 189 
J 0
(-1661 1500);
DISPLAY 0.638298 (-1661 1500);
PAINT MONO (-1661 1500);
FORCEPROP 2 LAST CDS_LIB standard
J 2
(-1875 1500);
DISPLAY INVISIBLE (-1875 1500);
FORCEPROP 1 LAST OFFPAGE TRUE
J 0
(-1550 1375);
DISPLAY 0.872340 (-1550 1375);
PAINT GREEN (-1550 1375);
DISPLAY INVISIBLE (-1550 1375);
FORCEPROP 1 LAST COMMENT_BODY TRUE
J 0
(-1925 1400);
DISPLAY 0.872340 (-1925 1400);
PAINT GREEN (-1925 1400);
DISPLAY INVISIBLE (-1925 1400);
FORCEPROP 2 LAST PATH I48
J 0
(-1650 1550);
DISPLAY 1.021277 (-1650 1550);
DISPLAY INVISIBLE (-1650 1550);
FORCEADD VCC_CORE..1
(-3975 2925);
FORCEPROP 3 LASTPIN (-3975 2875) SIG_NAME SW_P12V_STBY_PVDDCR_CPU0_P1_FLT\g
J 0
(-3965 2885);
DISPLAY 0.659574 (-3965 2885);
PAINT MONO (-3965 2885);
DISPLAY INVISIBLE (-3965 2885);
FORCEPROP 1 LAST HDL_POWER SW_P12V_STBY_PVDDCR_CPU0_P1_FLT
J 1
(-3975 2975);
DISPLAY 0.489362 (-3975 2975);
PAINT GREEN (-3975 2975);
FORCEPROP 2 LAST CDS_LIB pure_quanta_power
J 0
(-3975 2925);
DISPLAY INVISIBLE (-3975 2925);
FORCEPROP 1 LAST PATH I49
J 0
(-3925 2950);
DISPLAY 0.872340 (-3925 2950);
PAINT AQUA (-3925 2950);
DISPLAY INVISIBLE (-3925 2950);
FORCEADD UNIVERSAL_GND..1
(-7600 4175);
FORCEPROP 3 LASTPIN (-7600 4225) SIG_NAME GND\g
J 0
(-7590 4235);
DISPLAY 0.659574 (-7590 4235);
PAINT MONO (-7590 4235);
DISPLAY INVISIBLE (-7590 4235);
FORCEPROP 2 LAST CDS_LIB pure_quanta_power
J 0
(-7600 4175);
DISPLAY INVISIBLE (-7600 4175);
FORCEPROP 1 LAST PATH I5
J 0
(-7525 4175);
DISPLAY 0.872340 (-7525 4175);
PAINT AQUA (-7525 4175);
DISPLAY INVISIBLE (-7525 4175);
FORCEPROP 1 LAST HDL_POWER GND
J 1
(-7575 4100);
DISPLAY 0.872340 (-7575 4100);
PAINT GREEN (-7575 4100);
DISPLAY INVISIBLE (-7575 4100);
FORCEADD Q_CAP..1
(-3975 2625);
FORCEPROP 1 LAST LOCATION PC132_6
J 0
(-3925 2725);
DISPLAY 0.489362 (-3925 2725);
PAINT SKYBLUE (-3925 2725);
FORCEPROP 0 LAST $SEC 1
J 0
(-3925 2750);
DISPLAY 0.680851 (-3925 2750);
PAINT MONO (-3925 2750);
DISPLAY INVISIBLE (-3925 2750);
FORCEPROP 0 LAST CDS_SEC 1
J 0
(-3925 2750);
DISPLAY 1.021277 (-3925 2750);
DISPLAY INVISIBLE (-3925 2750);
FORCEPROP 1 LASTPIN (-3975 2725) $PN 1
J 0
(-3965 2705);
DISPLAY 0.489362 (-3965 2705);
PAINT MONO (-3965 2705);
FORCEPROP 1 LASTPIN (-3975 2525) $PN 2
J 0
(-3965 2505);
DISPLAY 0.489362 (-3965 2505);
PAINT MONO (-3965 2505);
FORCEPROP 1 LAST MATERIAL X6S
J 0
(-3925 2525);
DISPLAY 0.489362 (-3925 2525);
PAINT SKYBLUE (-3925 2525);
FORCEPROP 1 LAST TOLERANCE 10%
J 0
(-3925 2575);
DISPLAY 0.489362 (-3925 2575);
PAINT SKYBLUE (-3925 2575);
FORCEPROP 1 LAST VALUE 10UF
J 0
(-3925 2675);
DISPLAY 0.489362 (-3925 2675);
PAINT SKYBLUE (-3925 2675);
FORCEPROP 1 LAST PART_NUMBER CH6104KEA00
J 0
(-3925 2475);
DISPLAY 0.489362 (-3925 2475);
PAINT SKYBLUE (-3925 2475);
FORCEPROP 1 LAST VOLTAGE 25V
J 0
(-3925 2625);
DISPLAY 0.489362 (-3925 2625);
PAINT SKYBLUE (-3925 2625);
FORCEPROP 1 LAST PACK_TYPE C0805
J 0
(-3925 2425);
DISPLAY 0.489362 (-3925 2425);
PAINT SKYBLUE (-3925 2425);
FORCEPROP 2 LAST CDS_LIB pure_quanta
J 0
(-3975 2625);
DISPLAY INVISIBLE (-3975 2625);
FORCEPROP 1 LAST PATH I50
J 0
(-3925 2775);
DISPLAY 0.978723 (-3925 2775);
PAINT WHITE (-3925 2775);
DISPLAY INVISIBLE (-3925 2775);
FORCEADD UNIVERSAL_GND..1
(-3975 2275);
FORCEPROP 3 LASTPIN (-3975 2325) SIG_NAME GND\g
J 0
(-3965 2335);
DISPLAY 0.659574 (-3965 2335);
PAINT MONO (-3965 2335);
DISPLAY INVISIBLE (-3965 2335);
FORCEPROP 2 LAST CDS_LIB pure_quanta_power
J 0
(-3975 2275);
DISPLAY INVISIBLE (-3975 2275);
FORCEPROP 1 LAST PATH I51
J 0
(-3900 2275);
DISPLAY 0.872340 (-3900 2275);
PAINT AQUA (-3900 2275);
DISPLAY INVISIBLE (-3900 2275);
FORCEPROP 1 LAST HDL_POWER GND
J 1
(-3950 2200);
DISPLAY 0.872340 (-3950 2200);
PAINT GREEN (-3950 2200);
DISPLAY INVISIBLE (-3950 2200);
FORCEADD Q_INDUCTOR4P_14..1
(-2825 1625);
FORCEPROP 1 LAST LOCATION PL8
J 0
(-3050 1880);
DISPLAY 0.489362 (-3050 1880);
PAINT SKYBLUE (-3050 1880);
FORCEPROP 0 LAST $SEC 1
J 0
(-3050 2025);
DISPLAY 0.680851 (-3050 2025);
PAINT MONO (-3050 2025);
DISPLAY INVISIBLE (-3050 2025);
FORCEPROP 0 LAST CDS_SEC 1
J 0
(-3050 2025);
DISPLAY 1.021277 (-3050 2025);
DISPLAY INVISIBLE (-3050 2025);
FORCEPROP 0 LASTPIN (-3225 1750) $PN 1
J 2
(-3235 1760);
DISPLAY 0.489362 (-3235 1760);
PAINT MONO (-3235 1760);
FORCEPROP 0 LASTPIN (-3225 1500) $PN 2
J 2
(-3235 1510);
DISPLAY 0.489362 (-3235 1510);
PAINT MONO (-3235 1510);
FORCEPROP 0 LASTPIN (-2425 1500) $PN 3
J 0
(-2415 1510);
DISPLAY 0.489362 (-2415 1510);
PAINT MONO (-2415 1510);
FORCEPROP 0 LASTPIN (-2425 1750) $PN 4
J 0
(-2415 1760);
DISPLAY 0.489362 (-2415 1760);
PAINT MONO (-2415 1760);
FORCEPROP 2 LAST PART_TYPE SMLF
J 0
(-3050 1975);
DISPLAY 1.021277 (-3050 1975);
FORCEPROP 1 LAST MATERIAL IND
J 0
(-3050 1835);
DISPLAY 0.489362 (-3050 1835);
PAINT SKYBLUE (-3050 1835);
FORCEPROP 2 LAST VALUE 150NH
J 0
(-3050 1925);
DISPLAY 0.489362 (-3050 1925);
PAINT SKYBLUE (-3050 1925);
FORCEPROP 1 LAST PART_NUMBER CV+15^0TZ04
J 0
(-3050 1785);
DISPLAY 0.489362 (-3050 1785);
PAINT SKYBLUE (-3050 1785);
FORCEPROP 1 LAST NEEDS_NO_SIZE TRUE
J 0
(-2825 1625);
DISPLAY 0.468085 (-2825 1625);
PAINT GREEN (-2825 1625);
DISPLAY INVISIBLE (-2825 1625);
FORCEPROP 2 LAST CDS_LIB pure_quanta
J 0
(-2825 1625);
DISPLAY INVISIBLE (-2825 1625);
FORCEPROP 1 LAST PATH I52
J 0
(-2625 1780);
DISPLAY 0.723404 (-2625 1780);
PAINT GREEN (-2625 1780);
DISPLAY INVISIBLE (-2625 1780);
FORCEADD Q_CAP..1
(-3675 1975);
FORCEPROP 1 LAST LOCATION PC133
J 0
(-3625 2100);
DISPLAY 0.489362 (-3625 2100);
PAINT SKYBLUE (-3625 2100);
FORCEPROP 0 LAST $SEC 1
J 0
(-3625 2125);
DISPLAY 0.680851 (-3625 2125);
PAINT MONO (-3625 2125);
DISPLAY INVISIBLE (-3625 2125);
FORCEPROP 0 LAST CDS_SEC 1
J 0
(-3625 2125);
DISPLAY 1.021277 (-3625 2125);
DISPLAY INVISIBLE (-3625 2125);
FORCEPROP 1 LASTPIN (-3675 2075) $PN 1
J 0
(-3665 2055);
DISPLAY 0.489362 (-3665 2055);
PAINT MONO (-3665 2055);
FORCEPROP 1 LASTPIN (-3675 1875) $PN 2
J 0
(-3665 1855);
DISPLAY 0.489362 (-3665 1855);
PAINT MONO (-3665 1855);
FORCEPROP 1 LAST MATERIAL X7R
J 0
(-3625 1900);
DISPLAY 0.489362 (-3625 1900);
PAINT SKYBLUE (-3625 1900);
FORCEPROP 1 LAST TOLERANCE 10%
J 0
(-3625 1950);
DISPLAY 0.489362 (-3625 1950);
PAINT SKYBLUE (-3625 1950);
FORCEPROP 1 LAST VALUE 0.22UF
J 0
(-3625 2050);
DISPLAY 0.489362 (-3625 2050);
PAINT SKYBLUE (-3625 2050);
FORCEPROP 1 LAST PART_NUMBER CH4223K1B00
J 0
(-3625 1850);
DISPLAY 0.489362 (-3625 1850);
PAINT SKYBLUE (-3625 1850);
FORCEPROP 1 LAST VOLTAGE 16V
J 0
(-3625 2000);
DISPLAY 0.489362 (-3625 2000);
PAINT SKYBLUE (-3625 2000);
FORCEPROP 1 LAST PACK_TYPE 0402
J 0
(-3625 1800);
DISPLAY 0.489362 (-3625 1800);
PAINT SKYBLUE (-3625 1800);
FORCEPROP 2 LAST CDS_LIB pure_quanta
J 0
(-3675 1975);
DISPLAY INVISIBLE (-3675 1975);
FORCEPROP 1 LAST PATH I53
J 0
(-3625 2125);
DISPLAY 0.978723 (-3625 2125);
PAINT WHITE (-3625 2125);
DISPLAY INVISIBLE (-3625 2125);
FORCEADD Q_CAP..1
(-4275 2625);
FORCEPROP 1 LAST LOCATION PC130_6
J 0
(-4225 2725);
DISPLAY 0.489362 (-4225 2725);
PAINT SKYBLUE (-4225 2725);
FORCEPROP 0 LAST $SEC 1
J 0
(-4225 2750);
DISPLAY 0.680851 (-4225 2750);
PAINT MONO (-4225 2750);
DISPLAY INVISIBLE (-4225 2750);
FORCEPROP 0 LAST CDS_SEC 1
J 0
(-4225 2750);
DISPLAY 1.021277 (-4225 2750);
DISPLAY INVISIBLE (-4225 2750);
FORCEPROP 1 LASTPIN (-4275 2725) $PN 1
J 0
(-4265 2705);
DISPLAY 0.489362 (-4265 2705);
PAINT MONO (-4265 2705);
FORCEPROP 1 LASTPIN (-4275 2525) $PN 2
J 0
(-4265 2505);
DISPLAY 0.489362 (-4265 2505);
PAINT MONO (-4265 2505);
FORCEPROP 1 LAST MATERIAL X6S
J 0
(-4225 2525);
DISPLAY 0.489362 (-4225 2525);
PAINT SKYBLUE (-4225 2525);
FORCEPROP 1 LAST TOLERANCE 10%
J 0
(-4225 2575);
DISPLAY 0.489362 (-4225 2575);
PAINT SKYBLUE (-4225 2575);
FORCEPROP 1 LAST VALUE 10UF
J 0
(-4225 2675);
DISPLAY 0.489362 (-4225 2675);
PAINT SKYBLUE (-4225 2675);
FORCEPROP 1 LAST PART_NUMBER CH6104KEA00
J 0
(-4225 2475);
DISPLAY 0.489362 (-4225 2475);
PAINT SKYBLUE (-4225 2475);
FORCEPROP 1 LAST VOLTAGE 25V
J 0
(-4225 2625);
DISPLAY 0.489362 (-4225 2625);
PAINT SKYBLUE (-4225 2625);
FORCEPROP 1 LAST PACK_TYPE C0805
J 0
(-4225 2425);
DISPLAY 0.489362 (-4225 2425);
PAINT SKYBLUE (-4225 2425);
FORCEPROP 2 LAST CDS_LIB pure_quanta
J 0
(-4275 2625);
DISPLAY INVISIBLE (-4275 2625);
FORCEPROP 1 LAST PATH I55
J 0
(-4225 2775);
DISPLAY 0.978723 (-4225 2775);
PAINT WHITE (-4225 2775);
DISPLAY INVISIBLE (-4225 2775);
FORCEADD Q_CAP..1
(-4600 2625);
FORCEPROP 1 LAST LOCATION PC129_6
J 0
(-4550 2725);
DISPLAY 0.489362 (-4550 2725);
PAINT SKYBLUE (-4550 2725);
FORCEPROP 0 LAST $SEC 1
J 0
(-4550 2750);
DISPLAY 0.680851 (-4550 2750);
PAINT MONO (-4550 2750);
DISPLAY INVISIBLE (-4550 2750);
FORCEPROP 0 LAST CDS_SEC 1
J 0
(-4550 2750);
DISPLAY 1.021277 (-4550 2750);
DISPLAY INVISIBLE (-4550 2750);
FORCEPROP 1 LASTPIN (-4600 2725) $PN 1
J 0
(-4590 2705);
DISPLAY 0.489362 (-4590 2705);
PAINT MONO (-4590 2705);
FORCEPROP 1 LASTPIN (-4600 2525) $PN 2
J 0
(-4590 2505);
DISPLAY 0.489362 (-4590 2505);
PAINT MONO (-4590 2505);
FORCEPROP 1 LAST MATERIAL X6S
J 0
(-4550 2525);
DISPLAY 0.489362 (-4550 2525);
PAINT SKYBLUE (-4550 2525);
FORCEPROP 1 LAST TOLERANCE 10%
J 0
(-4550 2575);
DISPLAY 0.489362 (-4550 2575);
PAINT SKYBLUE (-4550 2575);
FORCEPROP 1 LAST VALUE 10UF
J 0
(-4550 2675);
DISPLAY 0.489362 (-4550 2675);
PAINT SKYBLUE (-4550 2675);
FORCEPROP 1 LAST PART_NUMBER CH6104KEA00
J 0
(-4550 2475);
DISPLAY 0.489362 (-4550 2475);
PAINT SKYBLUE (-4550 2475);
FORCEPROP 1 LAST VOLTAGE 25V
J 0
(-4550 2625);
DISPLAY 0.489362 (-4550 2625);
PAINT SKYBLUE (-4550 2625);
FORCEPROP 1 LAST PACK_TYPE C0805
J 0
(-4550 2425);
DISPLAY 0.489362 (-4550 2425);
PAINT SKYBLUE (-4550 2425);
FORCEPROP 2 LAST CDS_LIB pure_quanta
J 0
(-4600 2625);
DISPLAY INVISIBLE (-4600 2625);
FORCEPROP 1 LAST PATH I56
J 0
(-4550 2775);
DISPLAY 0.978723 (-4550 2775);
PAINT WHITE (-4550 2775);
DISPLAY INVISIBLE (-4550 2775);
FORCEADD Q_CAP..1
(-4925 2625);
FORCEPROP 1 LAST LOCATION PC128_6
J 0
(-4875 2725);
DISPLAY 0.489362 (-4875 2725);
PAINT SKYBLUE (-4875 2725);
FORCEPROP 0 LAST $SEC 1
J 0
(-4875 2750);
DISPLAY 0.680851 (-4875 2750);
PAINT MONO (-4875 2750);
DISPLAY INVISIBLE (-4875 2750);
FORCEPROP 0 LAST CDS_SEC 1
J 0
(-4875 2750);
DISPLAY 1.021277 (-4875 2750);
DISPLAY INVISIBLE (-4875 2750);
FORCEPROP 1 LASTPIN (-4925 2725) $PN 1
J 0
(-4915 2705);
DISPLAY 0.489362 (-4915 2705);
PAINT MONO (-4915 2705);
FORCEPROP 1 LASTPIN (-4925 2525) $PN 2
J 0
(-4915 2505);
DISPLAY 0.489362 (-4915 2505);
PAINT MONO (-4915 2505);
FORCEPROP 1 LAST MATERIAL X6S
J 0
(-4875 2525);
DISPLAY 0.489362 (-4875 2525);
PAINT SKYBLUE (-4875 2525);
FORCEPROP 1 LAST TOLERANCE 10%
J 0
(-4875 2575);
DISPLAY 0.489362 (-4875 2575);
PAINT SKYBLUE (-4875 2575);
FORCEPROP 1 LAST VALUE 1UF
J 0
(-4875 2675);
DISPLAY 0.489362 (-4875 2675);
PAINT SKYBLUE (-4875 2675);
FORCEPROP 1 LAST PART_NUMBER CH5104KEB02
J 0
(-4875 2475);
DISPLAY 0.489362 (-4875 2475);
PAINT SKYBLUE (-4875 2475);
FORCEPROP 1 LAST VOLTAGE 25V
J 0
(-4875 2625);
DISPLAY 0.489362 (-4875 2625);
PAINT SKYBLUE (-4875 2625);
FORCEPROP 1 LAST PACK_TYPE C0402
J 0
(-4875 2425);
DISPLAY 0.489362 (-4875 2425);
PAINT SKYBLUE (-4875 2425);
FORCEPROP 2 LAST CDS_LIB pure_quanta
J 0
(-4925 2625);
DISPLAY INVISIBLE (-4925 2625);
FORCEPROP 1 LAST PATH I57
J 0
(-4875 2775);
DISPLAY 0.978723 (-4875 2775);
PAINT WHITE (-4875 2775);
DISPLAY INVISIBLE (-4875 2775);
FORCEADD Q_RES..1
(-4225 700);
FORCEPROP 1 LAST LOCATION PR425
J 0
(-4250 750);
DISPLAY 0.489362 (-4250 750);
PAINT SKYBLUE (-4250 750);
FORCEPROP 0 LAST $SEC 1
J 0
(-4225 775);
DISPLAY 0.680851 (-4225 775);
PAINT MONO (-4225 775);
DISPLAY INVISIBLE (-4225 775);
FORCEPROP 0 LAST CDS_SEC 1
J 0
(-4225 775);
DISPLAY 1.021277 (-4225 775);
DISPLAY INVISIBLE (-4225 775);
FORCEPROP 1 LASTPIN (-4325 700) $PN 1
J 0
(-4313 712);
DISPLAY 0.489362 (-4313 712);
PAINT MONO (-4313 712);
FORCEPROP 1 LASTPIN (-4125 700) $PN 2
J 0
(-4163 712);
DISPLAY 0.489362 (-4163 712);
PAINT MONO (-4163 712);
FORCEPROP 1 LAST TOLERANCE 5%
J 0
(-4100 725);
DISPLAY 0.489362 (-4100 725);
PAINT SKYBLUE (-4100 725);
FORCEPROP 1 LAST WATTAGE 1/16W
J 0
(-4125 650);
DISPLAY 0.489362 (-4125 650);
PAINT SKYBLUE (-4125 650);
FORCEPROP 1 LAST MATERIAL CHIP
J 0
(-4475 600);
DISPLAY 0.489362 (-4475 600);
PAINT SKYBLUE (-4475 600);
FORCEPROP 1 LAST VALUE 0
J 2
(-4350 725);
DISPLAY 0.489362 (-4350 725);
PAINT SKYBLUE (-4350 725);
FORCEPROP 1 LAST PART_NUMBER CS00002JB38
J 0
(-4475 650);
DISPLAY 0.489362 (-4475 650);
PAINT SKYBLUE (-4475 650);
FORCEPROP 1 LAST PACK_TYPE 0402LF
J 0
(-4125 600);
DISPLAY 0.489362 (-4125 600);
PAINT SKYBLUE (-4125 600);
FORCEPROP 2 LAST CDS_LIB pure_quanta
J 0
(-4225 700);
DISPLAY INVISIBLE (-4225 700);
FORCEPROP 1 LAST PATH I58
J 0
(-4275 850);
DISPLAY 0.978723 (-4275 850);
PAINT WHITE (-4275 850);
DISPLAY INVISIBLE (-4275 850);
FORCEADD Q_RES..1
(-4650 2100);
FORCEPROP 1 LAST LOCATION PR424
J 0
(-4675 2150);
DISPLAY 0.489362 (-4675 2150);
PAINT SKYBLUE (-4675 2150);
FORCEPROP 0 LAST $SEC 1
J 0
(-4625 2175);
DISPLAY 0.680851 (-4625 2175);
PAINT MONO (-4625 2175);
DISPLAY INVISIBLE (-4625 2175);
FORCEPROP 0 LAST CDS_SEC 1
J 0
(-4625 2175);
DISPLAY 1.021277 (-4625 2175);
DISPLAY INVISIBLE (-4625 2175);
FORCEPROP 1 LASTPIN (-4750 2100) $PN 1
J 0
(-4738 2112);
DISPLAY 0.489362 (-4738 2112);
PAINT MONO (-4738 2112);
FORCEPROP 1 LASTPIN (-4550 2100) $PN 2
J 0
(-4588 2112);
DISPLAY 0.489362 (-4588 2112);
PAINT MONO (-4588 2112);
FORCEPROP 1 LAST PACK_TYPE 0402LF
J 0
(-4550 2000);
DISPLAY 0.489362 (-4550 2000);
PAINT SKYBLUE (-4550 2000);
FORCEPROP 1 LAST TOLERANCE 1%
J 0
(-4550 2125);
DISPLAY 0.489362 (-4550 2125);
PAINT SKYBLUE (-4550 2125);
FORCEPROP 1 LAST MATERIAL CHIP
J 0
(-4900 2000);
DISPLAY 0.489362 (-4900 2000);
PAINT SKYBLUE (-4900 2000);
FORCEPROP 1 LAST WATTAGE 1/16W
J 0
(-4550 2050);
DISPLAY 0.489362 (-4550 2050);
PAINT SKYBLUE (-4550 2050);
FORCEPROP 1 LAST VALUE 4.7
J 2
(-4750 2125);
DISPLAY 0.489362 (-4750 2125);
PAINT SKYBLUE (-4750 2125);
FORCEPROP 1 LAST PART_NUMBER CS-4702FB19
J 0
(-4900 2050);
DISPLAY 0.489362 (-4900 2050);
PAINT SKYBLUE (-4900 2050);
FORCEPROP 1 LAST PATH I59
J 0
(-4700 2250);
DISPLAY 0.978723 (-4700 2250);
PAINT WHITE (-4700 2250);
DISPLAY INVISIBLE (-4700 2250);
FORCEPROP 2 LAST CDS_LIB pure_quanta
J 0
(-4650 2100);
DISPLAY INVISIBLE (-4650 2100);
FORCEADD OFFPAGE..2
R 2
(-7225 4150);
FORCEPROP 2 LAST $XR3 186 
J 0
(-7720 4114);
DISPLAY 0.638298 (-7720 4114);
PAINT MONO (-7720 4114);
FORCEPROP 2 LAST $XR2 189 
J 0
(-7600 4114);
DISPLAY 0.638298 (-7600 4114);
PAINT MONO (-7600 4114);
FORCEPROP 2 LAST $XR1 188 
J 0
(-7480 4114);
DISPLAY 0.638298 (-7480 4114);
PAINT MONO (-7480 4114);
FORCEPROP 2 LAST $XR0 187 
J 0
(-7480 4150);
DISPLAY 0.638298 (-7480 4150);
PAINT MONO (-7480 4150);
FORCEPROP 2 LAST CDS_LIB standard
J 0
(-7225 4150);
DISPLAY INVISIBLE (-7225 4150);
FORCEPROP 1 LAST OFFPAGE TRUE
J 2
(-7550 4025);
DISPLAY 0.872340 (-7550 4025);
PAINT GREEN (-7550 4025);
DISPLAY INVISIBLE (-7550 4025);
FORCEPROP 1 LAST COMMENT_BODY TRUE
J 2
(-7180 4055);
DISPLAY 0.872340 (-7180 4055);
PAINT GREEN (-7180 4055);
DISPLAY INVISIBLE (-7180 4055);
FORCEPROP 2 LAST PATH I6
J 0
(-7175 4225);
DISPLAY 1.021277 (-7175 4225);
DISPLAY INVISIBLE (-7175 4225);
FORCEADD Q_CAP..1
(-5300 2625);
FORCEPROP 1 LAST LOCATION PC127_6
J 0
(-5250 2725);
DISPLAY 0.489362 (-5250 2725);
PAINT SKYBLUE (-5250 2725);
FORCEPROP 0 LAST $SEC 1
J 0
(-5250 2775);
DISPLAY 0.680851 (-5250 2775);
PAINT MONO (-5250 2775);
DISPLAY INVISIBLE (-5250 2775);
FORCEPROP 0 LAST CDS_SEC 1
J 0
(-5250 2775);
DISPLAY 1.021277 (-5250 2775);
DISPLAY INVISIBLE (-5250 2775);
FORCEPROP 1 LASTPIN (-5300 2725) $PN 1
J 0
(-5290 2705);
DISPLAY 0.489362 (-5290 2705);
PAINT MONO (-5290 2705);
FORCEPROP 1 LASTPIN (-5300 2525) $PN 2
J 0
(-5290 2505);
DISPLAY 0.489362 (-5290 2505);
PAINT MONO (-5290 2505);
FORCEPROP 1 LAST MATERIAL X7R
J 0
(-5250 2525);
DISPLAY 0.489362 (-5250 2525);
PAINT SKYBLUE (-5250 2525);
FORCEPROP 1 LAST TOLERANCE 10%
J 0
(-5250 2575);
DISPLAY 0.489362 (-5250 2575);
PAINT SKYBLUE (-5250 2575);
FORCEPROP 1 LAST VALUE 0.1UF
J 0
(-5250 2675);
DISPLAY 0.489362 (-5250 2675);
PAINT SKYBLUE (-5250 2675);
FORCEPROP 1 LAST PART_NUMBER CH4104K1B00
J 0
(-5250 2475);
DISPLAY 0.489362 (-5250 2475);
PAINT SKYBLUE (-5250 2475);
FORCEPROP 1 LAST VOLTAGE 25V
J 0
(-5250 2625);
DISPLAY 0.489362 (-5250 2625);
PAINT SKYBLUE (-5250 2625);
FORCEPROP 1 LAST PACK_TYPE 0402
J 0
(-5250 2425);
DISPLAY 0.489362 (-5250 2425);
PAINT SKYBLUE (-5250 2425);
FORCEPROP 2 LAST CDS_LIB pure_quanta
J 0
(-5300 2625);
DISPLAY INVISIBLE (-5300 2625);
FORCEPROP 1 LAST PATH I60
J 0
(-5250 2775);
DISPLAY 0.978723 (-5250 2775);
PAINT WHITE (-5250 2775);
DISPLAY INVISIBLE (-5250 2775);
FORCEADD VCC_CORE..1
(-7550 3050);
FORCEPROP 3 LASTPIN (-7550 3000) SIG_NAME PVDDCR_CPU0_P1_PVCC\g
J 0
(-7540 3010);
DISPLAY 0.659574 (-7540 3010);
PAINT MONO (-7540 3010);
DISPLAY INVISIBLE (-7540 3010);
FORCEPROP 1 LAST HDL_POWER PVDDCR_CPU0_P1_PVCC
J 1
(-7550 3100);
DISPLAY 0.489362 (-7550 3100);
PAINT GREEN (-7550 3100);
FORCEPROP 2 LAST CDS_LIB pure_quanta_power
J 0
(-7550 3050);
DISPLAY INVISIBLE (-7550 3050);
FORCEPROP 1 LAST PATH I61
J 0
(-7500 3075);
DISPLAY 0.872340 (-7500 3075);
PAINT AQUA (-7500 3075);
DISPLAY INVISIBLE (-7500 3075);
FORCEADD Q_CAP..1
(-7200 2675);
FORCEPROP 1 LAST LOCATION PC126_C0P1_6
J 0
(-7150 2775);
DISPLAY 0.489362 (-7150 2775);
PAINT SKYBLUE (-7150 2775);
FORCEPROP 0 LAST $SEC 1
J 0
(-7150 2825);
DISPLAY 0.680851 (-7150 2825);
PAINT MONO (-7150 2825);
DISPLAY INVISIBLE (-7150 2825);
FORCEPROP 0 LAST CDS_SEC 1
J 0
(-7150 2825);
DISPLAY 1.021277 (-7150 2825);
DISPLAY INVISIBLE (-7150 2825);
FORCEPROP 1 LASTPIN (-7200 2775) $PN 1
J 0
(-7190 2755);
DISPLAY 0.489362 (-7190 2755);
PAINT MONO (-7190 2755);
FORCEPROP 1 LASTPIN (-7200 2575) $PN 2
J 0
(-7190 2555);
DISPLAY 0.489362 (-7190 2555);
PAINT MONO (-7190 2555);
FORCEPROP 1 LAST MATERIAL X6S
J 0
(-7150 2575);
DISPLAY 0.489362 (-7150 2575);
PAINT SKYBLUE (-7150 2575);
FORCEPROP 1 LAST TOLERANCE 10%
J 0
(-7150 2625);
DISPLAY 0.489362 (-7150 2625);
PAINT SKYBLUE (-7150 2625);
FORCEPROP 1 LAST VALUE 2.2UF
J 0
(-7150 2725);
DISPLAY 0.489362 (-7150 2725);
PAINT SKYBLUE (-7150 2725);
FORCEPROP 1 LAST PART_NUMBER CH5222KEB01
J 0
(-7150 2525);
DISPLAY 0.489362 (-7150 2525);
PAINT SKYBLUE (-7150 2525);
FORCEPROP 1 LAST VOLTAGE 10V
J 0
(-7150 2675);
DISPLAY 0.489362 (-7150 2675);
PAINT SKYBLUE (-7150 2675);
FORCEPROP 1 LAST PACK_TYPE C0402
J 0
(-7150 2475);
DISPLAY 0.489362 (-7150 2475);
PAINT SKYBLUE (-7150 2475);
FORCEPROP 2 LAST CDS_LIB pure_quanta
J 0
(-7200 2675);
DISPLAY INVISIBLE (-7200 2675);
FORCEPROP 1 LAST PATH I62
J 0
(-7150 2825);
DISPLAY 0.978723 (-7150 2825);
PAINT WHITE (-7150 2825);
DISPLAY INVISIBLE (-7150 2825);
FORCEADD UNIVERSAL_GND..1
(-7200 2400);
FORCEPROP 3 LASTPIN (-7200 2450) SIG_NAME GND\g
J 0
(-7190 2460);
DISPLAY 0.659574 (-7190 2460);
PAINT MONO (-7190 2460);
DISPLAY INVISIBLE (-7190 2460);
FORCEPROP 2 LAST CDS_LIB pure_quanta_power
J 0
(-7200 2400);
DISPLAY INVISIBLE (-7200 2400);
FORCEPROP 1 LAST PATH I63
J 0
(-7125 2400);
DISPLAY 0.872340 (-7125 2400);
PAINT AQUA (-7125 2400);
DISPLAY INVISIBLE (-7125 2400);
FORCEPROP 1 LAST HDL_POWER GND
J 1
(-7175 2325);
DISPLAY 0.872340 (-7175 2325);
PAINT GREEN (-7175 2325);
DISPLAY INVISIBLE (-7175 2325);
FORCEADD Q_RES..2
(-7550 2650);
FORCEPROP 1 LAST LOCATION PR422
J 0
(-7505 2775);
DISPLAY 0.489362 (-7505 2775);
PAINT SKYBLUE (-7505 2775);
FORCEPROP 0 LAST $SEC 1
J 0
(-7500 2825);
DISPLAY 0.680851 (-7500 2825);
PAINT MONO (-7500 2825);
DISPLAY INVISIBLE (-7500 2825);
FORCEPROP 0 LAST CDS_SEC 1
J 0
(-7500 2825);
DISPLAY 1.021277 (-7500 2825);
DISPLAY INVISIBLE (-7500 2825);
FORCEPROP 1 LASTPIN (-7550 2750) $PN 1
J 0
(-7545 2712);
DISPLAY 0.489362 (-7545 2712);
PAINT MONO (-7545 2712);
FORCEPROP 1 LASTPIN (-7550 2550) $PN 2
J 0
(-7545 2560);
DISPLAY 0.489362 (-7545 2560);
PAINT MONO (-7545 2560);
FORCEPROP 1 LAST WATTAGE 1/16W
J 0
(-7500 2625);
DISPLAY 0.489362 (-7500 2625);
PAINT SKYBLUE (-7500 2625);
FORCEPROP 1 LAST MATERIAL CHIP
J 0
(-7500 2575);
DISPLAY 0.489362 (-7500 2575);
PAINT SKYBLUE (-7500 2575);
FORCEPROP 1 LAST TOLERANCE 1%
J 0
(-7500 2675);
DISPLAY 0.489362 (-7500 2675);
PAINT SKYBLUE (-7500 2675);
FORCEPROP 1 LAST VALUE 2.2
J 0
(-7500 2725);
DISPLAY 0.489362 (-7500 2725);
PAINT SKYBLUE (-7500 2725);
FORCEPROP 1 LAST PART_NUMBER CS-2202FB00
J 0
(-7500 2525);
DISPLAY 0.489362 (-7500 2525);
PAINT SKYBLUE (-7500 2525);
FORCEPROP 1 LAST PACK_TYPE 0402LF
J 0
(-7500 2475);
DISPLAY 0.489362 (-7500 2475);
PAINT SKYBLUE (-7500 2475);
FORCEPROP 2 LAST CDS_LIB pure_quanta
J 0
(-7550 2650);
DISPLAY INVISIBLE (-7550 2650);
FORCEPROP 1 LAST PATH I64
J 0
(-7500 2825);
DISPLAY 0.978723 (-7500 2825);
PAINT WHITE (-7500 2825);
DISPLAY INVISIBLE (-7500 2825);
FORCEADD OFFPAGE..2
R 2
(-7200 1750);
FORCEPROP 2 LAST $XR0 186 
J 0
(-7455 1750);
DISPLAY 0.638298 (-7455 1750);
PAINT MONO (-7455 1750);
FORCEPROP 2 LAST CDS_LIB standard
J 2
(-7200 1750);
DISPLAY INVISIBLE (-7200 1750);
FORCEPROP 1 LAST OFFPAGE TRUE
J 2
(-7525 1625);
DISPLAY 0.872340 (-7525 1625);
PAINT GREEN (-7525 1625);
DISPLAY INVISIBLE (-7525 1625);
FORCEPROP 1 LAST COMMENT_BODY TRUE
J 2
(-7155 1655);
DISPLAY 0.872340 (-7155 1655);
PAINT GREEN (-7155 1655);
DISPLAY INVISIBLE (-7155 1655);
FORCEPROP 2 LAST PATH I65
J 0
(-7450 1800);
DISPLAY 1.021277 (-7450 1800);
DISPLAY INVISIBLE (-7450 1800);
FORCEADD Q_CAP..1
(-7550 2100);
FORCEPROP 1 LAST LOCATION PC125
J 0
(-7500 2200);
DISPLAY 0.489362 (-7500 2200);
PAINT SKYBLUE (-7500 2200);
FORCEPROP 0 LAST $SEC 1
J 0
(-7500 2250);
DISPLAY 0.680851 (-7500 2250);
PAINT MONO (-7500 2250);
DISPLAY INVISIBLE (-7500 2250);
FORCEPROP 0 LAST CDS_SEC 1
J 0
(-7500 2250);
DISPLAY 1.021277 (-7500 2250);
DISPLAY INVISIBLE (-7500 2250);
FORCEPROP 1 LASTPIN (-7550 2200) $PN 1
J 0
(-7540 2180);
DISPLAY 0.489362 (-7540 2180);
PAINT MONO (-7540 2180);
FORCEPROP 1 LASTPIN (-7550 2000) $PN 2
J 0
(-7540 1980);
DISPLAY 0.489362 (-7540 1980);
PAINT MONO (-7540 1980);
FORCEPROP 1 LAST MATERIAL X6S
J 0
(-7500 2000);
DISPLAY 0.489362 (-7500 2000);
PAINT SKYBLUE (-7500 2000);
FORCEPROP 1 LAST TOLERANCE 10%
J 0
(-7500 2050);
DISPLAY 0.489362 (-7500 2050);
PAINT SKYBLUE (-7500 2050);
FORCEPROP 1 LAST VALUE 2.2UF
J 0
(-7500 2150);
DISPLAY 0.489362 (-7500 2150);
PAINT SKYBLUE (-7500 2150);
FORCEPROP 1 LAST PART_NUMBER CH5222KEB01
J 0
(-7500 1950);
DISPLAY 0.489362 (-7500 1950);
PAINT SKYBLUE (-7500 1950);
FORCEPROP 1 LAST VOLTAGE 10V
J 0
(-7500 2100);
DISPLAY 0.489362 (-7500 2100);
PAINT SKYBLUE (-7500 2100);
FORCEPROP 1 LAST PACK_TYPE C0402
J 0
(-7500 1900);
DISPLAY 0.489362 (-7500 1900);
PAINT SKYBLUE (-7500 1900);
FORCEPROP 2 LAST CDS_LIB pure_quanta
J 0
(-7550 2100);
DISPLAY INVISIBLE (-7550 2100);
FORCEPROP 1 LAST PATH I66
J 0
(-7500 2250);
DISPLAY 0.978723 (-7500 2250);
PAINT WHITE (-7500 2250);
DISPLAY INVISIBLE (-7500 2250);
FORCEADD UNIVERSAL_GND..1
(-7550 1900);
FORCEPROP 3 LASTPIN (-7550 1950) SIG_NAME GND\g
J 0
(-7540 1960);
DISPLAY 0.659574 (-7540 1960);
PAINT MONO (-7540 1960);
DISPLAY INVISIBLE (-7540 1960);
FORCEPROP 2 LAST CDS_LIB pure_quanta_power
J 0
(-7550 1900);
DISPLAY INVISIBLE (-7550 1900);
FORCEPROP 1 LAST PATH I67
J 0
(-7475 1900);
DISPLAY 0.872340 (-7475 1900);
PAINT AQUA (-7475 1900);
DISPLAY INVISIBLE (-7475 1900);
FORCEPROP 1 LAST HDL_POWER GND
J 1
(-7525 1825);
DISPLAY 0.872340 (-7525 1825);
PAINT GREEN (-7525 1825);
DISPLAY INVISIBLE (-7525 1825);
FORCEADD Q_RES..1
(-7225 1450);
FORCEPROP 1 LAST LOCATION PR423
J 0
(-7250 1500);
DISPLAY 0.489362 (-7250 1500);
PAINT SKYBLUE (-7250 1500);
FORCEPROP 0 LAST $SEC 1
J 0
(-7225 1525);
DISPLAY 0.680851 (-7225 1525);
PAINT MONO (-7225 1525);
DISPLAY INVISIBLE (-7225 1525);
FORCEPROP 0 LAST CDS_SEC 1
J 0
(-7225 1525);
DISPLAY 1.021277 (-7225 1525);
DISPLAY INVISIBLE (-7225 1525);
FORCEPROP 1 LASTPIN (-7325 1450) $PN 1
J 0
(-7313 1462);
DISPLAY 0.489362 (-7313 1462);
PAINT MONO (-7313 1462);
FORCEPROP 1 LASTPIN (-7125 1450) $PN 2
J 0
(-7163 1462);
DISPLAY 0.489362 (-7163 1462);
PAINT MONO (-7163 1462);
FORCEPROP 1 LAST WATTAGE 1/16W
J 0
(-7125 1350);
DISPLAY 0.489362 (-7125 1350);
PAINT SKYBLUE (-7125 1350);
FORCEPROP 1 LAST MATERIAL EMPTY
J 0
(-7525 1350);
DISPLAY 0.489362 (-7525 1350);
PAINT RED (-7525 1350);
FORCEPROP 1 LAST TOLERANCE 1%
J 0
(-7100 1475);
DISPLAY 0.489362 (-7100 1475);
PAINT SKYBLUE (-7100 1475);
FORCEPROP 1 LAST VALUE 8.87K
J 2
(-7350 1475);
DISPLAY 0.489362 (-7350 1475);
PAINT SKYBLUE (-7350 1475);
FORCEPROP 1 LAST PART_NUMBER CS28872FB01
J 0
(-7525 1400);
DISPLAY 0.489362 (-7525 1400);
PAINT SKYBLUE (-7525 1400);
FORCEPROP 1 LAST PACK_TYPE 0402LF
J 0
(-7125 1400);
DISPLAY 0.489362 (-7125 1400);
PAINT SKYBLUE (-7125 1400);
FORCEPROP 2 LAST CDS_LIB pure_quanta
J 0
(-7225 1450);
DISPLAY INVISIBLE (-7225 1450);
FORCEPROP 1 LAST PATH I68
J 0
(-7275 1600);
DISPLAY 0.978723 (-7275 1600);
PAINT WHITE (-7275 1600);
DISPLAY INVISIBLE (-7275 1600);
FORCEADD OFFPAGE..2
R 2
(-7175 1250);
FORCEPROP 2 LAST $XR3 186 
J 0
(-7700 1214);
DISPLAY 0.638298 (-7700 1214);
PAINT MONO (-7700 1214);
FORCEPROP 2 LAST $XR2 189 
J 0
(-7580 1214);
DISPLAY 0.638298 (-7580 1214);
PAINT MONO (-7580 1214);
FORCEPROP 2 LAST $XR1 188 
J 0
(-7460 1214);
DISPLAY 0.638298 (-7460 1214);
PAINT MONO (-7460 1214);
FORCEPROP 2 LAST $XR0 187 
J 0
(-7460 1250);
DISPLAY 0.638298 (-7460 1250);
PAINT MONO (-7460 1250);
FORCEPROP 2 LAST CDS_LIB standard
J 0
(-7175 1250);
DISPLAY INVISIBLE (-7175 1250);
FORCEPROP 1 LAST OFFPAGE TRUE
J 2
(-7500 1125);
DISPLAY 0.872340 (-7500 1125);
PAINT GREEN (-7500 1125);
DISPLAY INVISIBLE (-7500 1125);
FORCEPROP 1 LAST COMMENT_BODY TRUE
J 2
(-7130 1155);
DISPLAY 0.872340 (-7130 1155);
PAINT GREEN (-7130 1155);
DISPLAY INVISIBLE (-7130 1155);
FORCEPROP 2 LAST PATH I69
J 0
(-7425 1300);
DISPLAY 1.021277 (-7425 1300);
DISPLAY INVISIBLE (-7425 1300);
FORCEADD UNIVERSAL_GND..1
(-7550 1275);
FORCEPROP 3 LASTPIN (-7550 1325) SIG_NAME GND\g
J 0
(-7540 1335);
DISPLAY 0.659574 (-7540 1335);
PAINT MONO (-7540 1335);
DISPLAY INVISIBLE (-7540 1335);
FORCEPROP 2 LAST CDS_LIB pure_quanta_power
J 0
(-7550 1275);
DISPLAY INVISIBLE (-7550 1275);
FORCEPROP 1 LAST PATH I70
J 0
(-7475 1275);
DISPLAY 0.872340 (-7475 1275);
PAINT AQUA (-7475 1275);
DISPLAY INVISIBLE (-7475 1275);
FORCEPROP 1 LAST HDL_POWER GND
J 1
(-7525 1200);
DISPLAY 0.872340 (-7525 1200);
PAINT GREEN (-7525 1200);
DISPLAY INVISIBLE (-7525 1200);
FORCEADD Q_CAP..1
(-7875 1475);
FORCEPROP 1 LAST LOCATION PC124_6
J 0
(-7825 1575);
DISPLAY 0.489362 (-7825 1575);
PAINT SKYBLUE (-7825 1575);
FORCEPROP 0 LAST $SEC 1
J 0
(-7825 1600);
DISPLAY 0.680851 (-7825 1600);
PAINT MONO (-7825 1600);
DISPLAY INVISIBLE (-7825 1600);
FORCEPROP 0 LAST CDS_SEC 1
J 0
(-7825 1600);
DISPLAY 1.021277 (-7825 1600);
DISPLAY INVISIBLE (-7825 1600);
FORCEPROP 1 LASTPIN (-7875 1575) $PN 1
J 0
(-7865 1555);
DISPLAY 0.489362 (-7865 1555);
PAINT MONO (-7865 1555);
FORCEPROP 1 LASTPIN (-7875 1375) $PN 2
J 0
(-7865 1355);
DISPLAY 0.489362 (-7865 1355);
PAINT MONO (-7865 1355);
FORCEPROP 1 LAST MATERIAL X7R
J 0
(-7825 1375);
DISPLAY 0.489362 (-7825 1375);
PAINT SKYBLUE (-7825 1375);
FORCEPROP 1 LAST TOLERANCE 10%
J 0
(-7825 1425);
DISPLAY 0.489362 (-7825 1425);
PAINT SKYBLUE (-7825 1425);
FORCEPROP 1 LAST VALUE 0.1UF
J 0
(-7825 1525);
DISPLAY 0.489362 (-7825 1525);
PAINT SKYBLUE (-7825 1525);
FORCEPROP 1 LAST PART_NUMBER CH4104K1B00
J 0
(-7825 1325);
DISPLAY 0.489362 (-7825 1325);
PAINT SKYBLUE (-7825 1325);
FORCEPROP 1 LAST VOLTAGE 25V
J 0
(-7825 1475);
DISPLAY 0.489362 (-7825 1475);
PAINT SKYBLUE (-7825 1475);
FORCEPROP 1 LAST PACK_TYPE 0402
J 0
(-7825 1275);
DISPLAY 0.489362 (-7825 1275);
PAINT SKYBLUE (-7825 1275);
FORCEPROP 2 LAST CDS_LIB pure_quanta
J 0
(-7875 1475);
DISPLAY INVISIBLE (-7875 1475);
FORCEPROP 1 LAST PATH I71
J 0
(-7825 1625);
DISPLAY 0.978723 (-7825 1625);
PAINT WHITE (-7825 1625);
DISPLAY INVISIBLE (-7825 1625);
FORCEADD UNIVERSAL_GND..1
(-5500 1025);
FORCEPROP 3 LASTPIN (-5500 1075) SIG_NAME GND\g
J 0
(-5490 1085);
DISPLAY 0.659574 (-5490 1085);
PAINT MONO (-5490 1085);
DISPLAY INVISIBLE (-5490 1085);
FORCEPROP 2 LAST CDS_LIB pure_quanta_power
J 0
(-5500 1025);
DISPLAY INVISIBLE (-5500 1025);
FORCEPROP 1 LAST PATH I72
J 0
(-5425 1025);
DISPLAY 0.872340 (-5425 1025);
PAINT AQUA (-5425 1025);
DISPLAY INVISIBLE (-5425 1025);
FORCEPROP 1 LAST HDL_POWER GND
J 1
(-5475 950);
DISPLAY 0.872340 (-5475 950);
PAINT GREEN (-5475 950);
DISPLAY INVISIBLE (-5475 950);
FORCEADD OFFPAGE..1
(-7150 1150);
FORCEPROP 2 LAST $XR0 186 
J 0
(-7432 1150);
DISPLAY 0.638298 (-7432 1150);
PAINT MONO (-7432 1150);
FORCEPROP 2 LAST CDS_LIB standard
J 2
(-7150 1150);
DISPLAY INVISIBLE (-7150 1150);
FORCEPROP 1 LAST OFFPAGE TRUE
J 0
(-6825 1025);
DISPLAY 0.872340 (-6825 1025);
PAINT GREEN (-6825 1025);
DISPLAY INVISIBLE (-6825 1025);
FORCEPROP 1 LAST COMMENT_BODY TRUE
J 0
(-7025 1050);
DISPLAY 0.872340 (-7025 1050);
PAINT GREEN (-7025 1050);
DISPLAY INVISIBLE (-7025 1050);
FORCEPROP 2 LAST PATH I73
J 0
(-7400 1200);
DISPLAY 1.021277 (-7400 1200);
DISPLAY INVISIBLE (-7400 1200);
FORCEADD UNIVERSAL_GND..1
(-7875 1200);
FORCEPROP 3 LASTPIN (-7875 1250) SIG_NAME GND\g
J 0
(-7865 1260);
DISPLAY 0.659574 (-7865 1260);
PAINT MONO (-7865 1260);
DISPLAY INVISIBLE (-7865 1260);
FORCEPROP 2 LAST CDS_LIB pure_quanta_power
J 0
(-7875 1200);
DISPLAY INVISIBLE (-7875 1200);
FORCEPROP 1 LAST PATH I74
J 0
(-7800 1200);
DISPLAY 0.872340 (-7800 1200);
PAINT AQUA (-7800 1200);
DISPLAY INVISIBLE (-7800 1200);
FORCEPROP 1 LAST HDL_POWER GND
J 1
(-7850 1125);
DISPLAY 0.872340 (-7850 1125);
PAINT GREEN (-7850 1125);
DISPLAY INVISIBLE (-7850 1125);
FORCEADD OFFPAGE..1
(-8100 1650);
FORCEPROP 2 LAST $XR5 192 
J 0
(-8952 1650);
DISPLAY 0.638298 (-8952 1650);
PAINT MONO (-8952 1650);
FORCEPROP 2 LAST $XR4 191 
J 0
(-8832 1650);
DISPLAY 0.638298 (-8832 1650);
PAINT MONO (-8832 1650);
FORCEPROP 2 LAST $XR3 189 
J 0
(-8712 1650);
DISPLAY 0.638298 (-8712 1650);
PAINT MONO (-8712 1650);
FORCEPROP 2 LAST $XR2 188 
J 0
(-8592 1650);
DISPLAY 0.638298 (-8592 1650);
PAINT MONO (-8592 1650);
FORCEPROP 2 LAST $XR1 187 
J 0
(-8472 1650);
DISPLAY 0.638298 (-8472 1650);
PAINT MONO (-8472 1650);
FORCEPROP 2 LAST $XR0 186 
J 0
(-8352 1650);
DISPLAY 0.638298 (-8352 1650);
PAINT MONO (-8352 1650);
FORCEPROP 2 LAST CDS_LIB standard
J 0
(-8100 1650);
DISPLAY INVISIBLE (-8100 1650);
FORCEPROP 1 LAST OFFPAGE TRUE
J 0
(-7775 1525);
DISPLAY 0.872340 (-7775 1525);
PAINT GREEN (-7775 1525);
DISPLAY INVISIBLE (-7775 1525);
FORCEPROP 1 LAST COMMENT_BODY TRUE
J 0
(-7975 1550);
DISPLAY 0.872340 (-7975 1550);
PAINT GREEN (-7975 1550);
DISPLAY INVISIBLE (-7975 1550);
FORCEPROP 2 LAST PATH I75
J 0
(-8375 1700);
DISPLAY 1.021277 (-8375 1700);
DISPLAY INVISIBLE (-8375 1700);
FORCEADD OFFPAGE..2
R 2
(-7250 4650);
FORCEPROP 2 LAST $XR0 186 
J 0
(-7505 4650);
DISPLAY 0.638298 (-7505 4650);
PAINT MONO (-7505 4650);
FORCEPROP 2 LAST CDS_LIB standard
J 2
(-7250 4650);
DISPLAY INVISIBLE (-7250 4650);
FORCEPROP 1 LAST OFFPAGE TRUE
J 2
(-7575 4525);
DISPLAY 0.872340 (-7575 4525);
PAINT GREEN (-7575 4525);
DISPLAY INVISIBLE (-7575 4525);
FORCEPROP 1 LAST COMMENT_BODY TRUE
J 2
(-7205 4555);
DISPLAY 0.872340 (-7205 4555);
PAINT GREEN (-7205 4555);
DISPLAY INVISIBLE (-7205 4555);
FORCEPROP 2 LAST PATH I8
J 0
(-7200 4725);
DISPLAY 1.021277 (-7200 4725);
DISPLAY INVISIBLE (-7200 4725);
FORCEADD Q_CAP..1
(-3725 4875);
FORCEPROP 1 LAST LOCATION PC314
J 0
(-3675 5000);
DISPLAY 0.489362 (-3675 5000);
PAINT SKYBLUE (-3675 5000);
FORCEPROP 0 LAST $SEC 1
J 0
(-3675 5025);
DISPLAY 0.680851 (-3675 5025);
PAINT MONO (-3675 5025);
DISPLAY INVISIBLE (-3675 5025);
FORCEPROP 0 LAST CDS_SEC 1
J 0
(-3675 5025);
DISPLAY 1.021277 (-3675 5025);
DISPLAY INVISIBLE (-3675 5025);
FORCEPROP 1 LASTPIN (-3725 4975) $PN 1
J 0
(-3715 4955);
DISPLAY 0.489362 (-3715 4955);
PAINT MONO (-3715 4955);
FORCEPROP 1 LASTPIN (-3725 4775) $PN 2
J 0
(-3715 4755);
DISPLAY 0.489362 (-3715 4755);
PAINT MONO (-3715 4755);
FORCEPROP 1 LAST MATERIAL X7R
J 0
(-3675 4800);
DISPLAY 0.489362 (-3675 4800);
PAINT SKYBLUE (-3675 4800);
FORCEPROP 1 LAST TOLERANCE 10%
J 0
(-3675 4850);
DISPLAY 0.489362 (-3675 4850);
PAINT SKYBLUE (-3675 4850);
FORCEPROP 1 LAST VALUE 0.22UF
J 0
(-3675 4950);
DISPLAY 0.489362 (-3675 4950);
PAINT SKYBLUE (-3675 4950);
FORCEPROP 1 LAST PART_NUMBER CH4223K1B00
J 0
(-3675 4750);
DISPLAY 0.489362 (-3675 4750);
PAINT SKYBLUE (-3675 4750);
FORCEPROP 1 LAST VOLTAGE 16V
J 0
(-3675 4900);
DISPLAY 0.489362 (-3675 4900);
PAINT SKYBLUE (-3675 4900);
FORCEPROP 1 LAST PACK_TYPE 0402
J 0
(-3675 4700);
DISPLAY 0.489362 (-3675 4700);
PAINT SKYBLUE (-3675 4700);
FORCEPROP 2 LAST CDS_LIB pure_quanta
J 0
(-3725 4875);
DISPLAY INVISIBLE (-3725 4875);
FORCEPROP 1 LAST PATH I80
J 0
(-3675 5025);
DISPLAY 0.978723 (-3675 5025);
PAINT WHITE (-3675 5025);
DISPLAY INVISIBLE (-3675 5025);
FORCEADD UNIVERSAL_GND..1
(-4625 825);
FORCEPROP 3 LASTPIN (-4625 875) SIG_NAME GND\g
J 0
(-4615 885);
DISPLAY 0.659574 (-4615 885);
PAINT MONO (-4615 885);
DISPLAY INVISIBLE (-4615 885);
FORCEPROP 2 LAST CDS_LIB pure_quanta_power
J 0
(-4625 825);
DISPLAY INVISIBLE (-4625 825);
FORCEPROP 1 LAST PATH I81
J 0
(-4550 825);
DISPLAY 0.872340 (-4550 825);
PAINT AQUA (-4550 825);
DISPLAY INVISIBLE (-4550 825);
FORCEPROP 1 LAST HDL_POWER GND
J 1
(-4600 750);
DISPLAY 0.872340 (-4600 750);
PAINT GREEN (-4600 750);
DISPLAY INVISIBLE (-4600 750);
FORCEADD Q_RES..2
(-4625 1050);
FORCEPROP 1 LAST LOCATION PR524
J 0
(-4580 1175);
DISPLAY 0.489362 (-4580 1175);
PAINT SKYBLUE (-4580 1175);
FORCEPROP 0 LAST $SEC 1
J 0
(-4575 1225);
DISPLAY 0.680851 (-4575 1225);
PAINT MONO (-4575 1225);
DISPLAY INVISIBLE (-4575 1225);
FORCEPROP 0 LAST CDS_SEC 1
J 0
(-4575 1225);
DISPLAY 1.021277 (-4575 1225);
DISPLAY INVISIBLE (-4575 1225);
FORCEPROP 1 LASTPIN (-4625 1150) $PN 1
J 0
(-4620 1112);
DISPLAY 0.489362 (-4620 1112);
PAINT MONO (-4620 1112);
FORCEPROP 1 LASTPIN (-4625 950) $PN 2
J 0
(-4620 960);
DISPLAY 0.489362 (-4620 960);
PAINT MONO (-4620 960);
FORCEPROP 1 LAST PART_NUMBER CS-1504FB00
J 0
(-4585 925);
DISPLAY 0.489362 (-4585 925);
PAINT SKYBLUE (-4585 925);
FORCEPROP 1 LAST WATTAGE 1/8W
J 0
(-4585 1025);
DISPLAY 0.489362 (-4585 1025);
PAINT SKYBLUE (-4585 1025);
FORCEPROP 1 LAST MATERIAL EMPTY
J 0
(-4585 975);
DISPLAY 0.489362 (-4585 975);
PAINT RED (-4585 975);
FORCEPROP 1 LAST TOLERANCE 1%
J 0
(-4580 1075);
DISPLAY 0.489362 (-4580 1075);
PAINT SKYBLUE (-4580 1075);
FORCEPROP 1 LAST VALUE 1.5
J 0
(-4580 1125);
DISPLAY 0.489362 (-4580 1125);
PAINT SKYBLUE (-4580 1125);
FORCEPROP 1 LAST PACK_TYPE 0402LF
J 0
(-4585 875);
DISPLAY 0.489362 (-4585 875);
PAINT SKYBLUE (-4585 875);
FORCEPROP 2 LAST CDS_LIB pure_quanta
J 0
(-4625 1050);
DISPLAY INVISIBLE (-4625 1050);
FORCEPROP 1 LAST PATH I82
J 0
(-4575 1225);
DISPLAY 0.978723 (-4575 1225);
PAINT WHITE (-4575 1225);
DISPLAY INVISIBLE (-4575 1225);
FORCEADD Q_CAP..1
(-4625 1550);
FORCEPROP 1 LAST LOCATION PC321
J 0
(-4575 1650);
DISPLAY 0.489362 (-4575 1650);
PAINT SKYBLUE (-4575 1650);
FORCEPROP 0 LAST $SEC 1
J 0
(-4575 1700);
DISPLAY 0.680851 (-4575 1700);
PAINT MONO (-4575 1700);
DISPLAY INVISIBLE (-4575 1700);
FORCEPROP 0 LAST CDS_SEC 1
J 0
(-4575 1700);
DISPLAY 1.021277 (-4575 1700);
DISPLAY INVISIBLE (-4575 1700);
FORCEPROP 1 LASTPIN (-4625 1650) $PN 1
J 0
(-4615 1630);
DISPLAY 0.489362 (-4615 1630);
PAINT MONO (-4615 1630);
FORCEPROP 1 LASTPIN (-4625 1450) $PN 2
J 0
(-4615 1430);
DISPLAY 0.489362 (-4615 1430);
PAINT MONO (-4615 1430);
FORCEPROP 1 LAST PART_NUMBER CH1566K1B09
J 0
(-4575 1400);
DISPLAY 0.489362 (-4575 1400);
PAINT SKYBLUE (-4575 1400);
FORCEPROP 1 LAST MATERIAL EMPTY
J 0
(-4575 1450);
DISPLAY 0.489362 (-4575 1450);
PAINT RED (-4575 1450);
FORCEPROP 1 LAST TOLERANCE 10%
J 0
(-4575 1500);
DISPLAY 0.489362 (-4575 1500);
PAINT SKYBLUE (-4575 1500);
FORCEPROP 1 LAST VALUE 560PF
J 0
(-4575 1600);
DISPLAY 0.489362 (-4575 1600);
PAINT SKYBLUE (-4575 1600);
FORCEPROP 1 LAST VOLTAGE 50V
J 0
(-4575 1550);
DISPLAY 0.489362 (-4575 1550);
PAINT SKYBLUE (-4575 1550);
FORCEPROP 1 LAST PACK_TYPE C0402
J 0
(-4575 1350);
DISPLAY 0.489362 (-4575 1350);
PAINT SKYBLUE (-4575 1350);
FORCEPROP 2 LAST CDS_LIB pure_quanta
J 0
(-4625 1550);
DISPLAY INVISIBLE (-4625 1550);
FORCEPROP 1 LAST PATH I83
J 0
(-4575 1700);
DISPLAY 0.978723 (-4575 1700);
PAINT WHITE (-4575 1700);
DISPLAY INVISIBLE (-4575 1700);
FORCEADD UNIVERSAL_GND..1
(-4675 3700);
FORCEPROP 3 LASTPIN (-4675 3750) SIG_NAME GND\g
J 0
(-4665 3760);
DISPLAY 0.659574 (-4665 3760);
PAINT MONO (-4665 3760);
DISPLAY INVISIBLE (-4665 3760);
FORCEPROP 2 LAST CDS_LIB pure_quanta_power
J 0
(-4675 3700);
DISPLAY INVISIBLE (-4675 3700);
FORCEPROP 1 LAST PATH I84
J 0
(-4600 3700);
DISPLAY 0.872340 (-4600 3700);
PAINT AQUA (-4600 3700);
DISPLAY INVISIBLE (-4600 3700);
FORCEPROP 1 LAST HDL_POWER GND
J 1
(-4650 3625);
DISPLAY 0.872340 (-4650 3625);
PAINT GREEN (-4650 3625);
DISPLAY INVISIBLE (-4650 3625);
FORCEADD Q_RES..2
(-4675 3925);
FORCEPROP 1 LAST LOCATION PR46
J 0
(-4630 4050);
DISPLAY 0.489362 (-4630 4050);
PAINT SKYBLUE (-4630 4050);
FORCEPROP 0 LAST $SEC 1
J 0
(-4625 4100);
DISPLAY 0.680851 (-4625 4100);
PAINT MONO (-4625 4100);
DISPLAY INVISIBLE (-4625 4100);
FORCEPROP 0 LAST CDS_SEC 1
J 0
(-4625 4100);
DISPLAY 1.021277 (-4625 4100);
DISPLAY INVISIBLE (-4625 4100);
FORCEPROP 1 LASTPIN (-4675 4025) $PN 1
J 0
(-4670 3987);
DISPLAY 0.489362 (-4670 3987);
PAINT MONO (-4670 3987);
FORCEPROP 1 LASTPIN (-4675 3825) $PN 2
J 0
(-4670 3835);
DISPLAY 0.489362 (-4670 3835);
PAINT MONO (-4670 3835);
FORCEPROP 1 LAST WATTAGE 1/8W
J 0
(-4635 3900);
DISPLAY 0.489362 (-4635 3900);
PAINT SKYBLUE (-4635 3900);
FORCEPROP 1 LAST MATERIAL EMPTY
J 0
(-4635 3850);
DISPLAY 0.489362 (-4635 3850);
PAINT RED (-4635 3850);
FORCEPROP 1 LAST TOLERANCE 1%
J 0
(-4630 3950);
DISPLAY 0.489362 (-4630 3950);
PAINT SKYBLUE (-4630 3950);
FORCEPROP 1 LAST VALUE 1.5
J 0
(-4630 4000);
DISPLAY 0.489362 (-4630 4000);
PAINT SKYBLUE (-4630 4000);
FORCEPROP 1 LAST PART_NUMBER CS-1504FB00
J 0
(-4635 3800);
DISPLAY 0.489362 (-4635 3800);
PAINT SKYBLUE (-4635 3800);
FORCEPROP 1 LAST PACK_TYPE 0402LF
J 0
(-4635 3750);
DISPLAY 0.489362 (-4635 3750);
PAINT SKYBLUE (-4635 3750);
FORCEPROP 2 LAST CDS_LIB pure_quanta
J 0
(-4675 3925);
DISPLAY INVISIBLE (-4675 3925);
FORCEPROP 1 LAST PATH I85
J 0
(-4625 4100);
DISPLAY 0.978723 (-4625 4100);
PAINT WHITE (-4625 4100);
DISPLAY INVISIBLE (-4625 4100);
FORCEADD Q_CAP..1
(-4675 4450);
FORCEPROP 1 LAST LOCATION PC318
J 0
(-4625 4550);
DISPLAY 0.489362 (-4625 4550);
PAINT SKYBLUE (-4625 4550);
FORCEPROP 0 LAST $SEC 1
J 0
(-4625 4600);
DISPLAY 0.680851 (-4625 4600);
PAINT MONO (-4625 4600);
DISPLAY INVISIBLE (-4625 4600);
FORCEPROP 0 LAST CDS_SEC 1
J 0
(-4625 4600);
DISPLAY 1.021277 (-4625 4600);
DISPLAY INVISIBLE (-4625 4600);
FORCEPROP 1 LASTPIN (-4675 4550) $PN 1
J 0
(-4665 4530);
DISPLAY 0.489362 (-4665 4530);
PAINT MONO (-4665 4530);
FORCEPROP 1 LASTPIN (-4675 4350) $PN 2
J 0
(-4665 4330);
DISPLAY 0.489362 (-4665 4330);
PAINT MONO (-4665 4330);
FORCEPROP 1 LAST MATERIAL EMPTY
J 0
(-4625 4350);
DISPLAY 0.489362 (-4625 4350);
PAINT RED (-4625 4350);
FORCEPROP 1 LAST TOLERANCE 10%
J 0
(-4625 4400);
DISPLAY 0.489362 (-4625 4400);
PAINT SKYBLUE (-4625 4400);
FORCEPROP 1 LAST VALUE 560PF
J 0
(-4625 4500);
DISPLAY 0.489362 (-4625 4500);
PAINT SKYBLUE (-4625 4500);
FORCEPROP 1 LAST PART_NUMBER CH1566K1B09
J 0
(-4625 4300);
DISPLAY 0.489362 (-4625 4300);
PAINT SKYBLUE (-4625 4300);
FORCEPROP 1 LAST VOLTAGE 50V
J 0
(-4625 4450);
DISPLAY 0.489362 (-4625 4450);
PAINT SKYBLUE (-4625 4450);
FORCEPROP 1 LAST PACK_TYPE C0402
J 0
(-4625 4250);
DISPLAY 0.489362 (-4625 4250);
PAINT SKYBLUE (-4625 4250);
FORCEPROP 2 LAST CDS_LIB pure_quanta
J 0
(-4675 4450);
DISPLAY INVISIBLE (-4675 4450);
FORCEPROP 1 LAST PATH I86
J 0
(-4625 4600);
DISPLAY 0.978723 (-4625 4600);
PAINT WHITE (-4625 4600);
DISPLAY INVISIBLE (-4625 4600);
FORCEADD Q_INDUCTOR..1
(-3800 1525);
FORCEPROP 1 LAST LOCATION PL27
J 0
(-3950 1675);
DISPLAY 0.489362 (-3950 1675);
PAINT SKYBLUE (-3950 1675);
FORCEPROP 0 LAST $SEC 1
J 0
(-3950 1700);
DISPLAY 0.680851 (-3950 1700);
PAINT MONO (-3950 1700);
DISPLAY INVISIBLE (-3950 1700);
FORCEPROP 0 LAST CDS_SEC 1
J 0
(-3950 1700);
DISPLAY 0.680851 (-3950 1700);
DISPLAY INVISIBLE (-3950 1700);
FORCEPROP 0 LASTPIN (-3900 1500) $PN 1
J 2
(-3910 1510);
DISPLAY 0.489362 (-3910 1510);
PAINT MONO (-3910 1510);
FORCEPROP 0 LASTPIN (-3700 1500) $PN 2
J 0
(-3690 1510);
DISPLAY 0.489362 (-3690 1510);
PAINT MONO (-3690 1510);
FORCEPROP 2 LAST PACK_TYPE SMLF
J 0
(-3950 1625);
DISPLAY 0.489362 (-3950 1625);
PAINT SKYBLUE (-3950 1625);
FORCEPROP 1 LAST MATERIAL IND
J 0
(-3950 1575);
DISPLAY 0.489362 (-3950 1575);
PAINT SKYBLUE (-3950 1575);
FORCEPROP 2 LASTPIN (-3700 1500) SIG_NAME IND_CPU0_P1_CPL0
J 0
(-3685 1510);
DISPLAY 0.489362 (-3685 1510);
FORCEPROP 2 LASTPROP $XRERR UNIQUE?
J 0
(-3925 1510);
DISPLAY 0.638298 (-3925 1510);
PAINT MONO (-3925 1510);
DISPLAY INVISIBLE (-3925 1510);
FORCEPROP 2 LAST VALUE 0.22UH/33A
J 0
(-3950 1650);
DISPLAY 0.489362 (-3950 1650);
PAINT SKYBLUE (-3950 1650);
FORCEPROP 1 LAST PART_NUMBER CV+22Y0EZ00
J 0
(-3950 1600);
DISPLAY 0.489362 (-3950 1600);
PAINT SKYBLUE (-3950 1600);
FORCEPROP 1 LAST PATH I87
J 0
(-3725 1580);
DISPLAY 0.723404 (-3725 1580);
PAINT GREEN (-3725 1580);
DISPLAY INVISIBLE (-3725 1580);
FORCEPROP 2 LAST CDS_LIB pure_quanta
J 0
(-3800 1525);
DISPLAY INVISIBLE (-3800 1525);
FORCEPROP 1 LAST NEEDS_NO_SIZE TRUE
J 0
(-3800 1525);
DISPLAY 0.468085 (-3800 1525);
PAINT GREEN (-3800 1525);
DISPLAY INVISIBLE (-3800 1525);
FORCEADD UNIVERSAL_GND..1
(-4100 1375);
FORCEPROP 3 LASTPIN (-4100 1425) SIG_NAME GND\g
J 0
(-4090 1435);
DISPLAY 0.659574 (-4090 1435);
PAINT MONO (-4090 1435);
DISPLAY INVISIBLE (-4090 1435);
FORCEPROP 2 LAST CDS_LIB pure_quanta_power
J 0
(-4100 1375);
DISPLAY INVISIBLE (-4100 1375);
FORCEPROP 1 LAST PATH I88
J 0
(-4025 1375);
DISPLAY 0.872340 (-4025 1375);
PAINT AQUA (-4025 1375);
DISPLAY INVISIBLE (-4025 1375);
FORCEPROP 1 LAST HDL_POWER GND
J 1
(-4075 1300);
DISPLAY 0.872340 (-4075 1300);
PAINT GREEN (-4075 1300);
DISPLAY INVISIBLE (-4075 1300);
FORCEADD DNS..1
(-4700 3925);
PAINT RED (-4700 3925);
FORCEPROP 2 LAST CDS_LIB mstr_misc
J 0
(-4700 3925);
DISPLAY INVISIBLE (-4700 3925);
FORCEPROP 1 LAST COMMENT_BODY TRUE
R 1
J 0
(-4625 3700);
DISPLAY 0.872340 (-4625 3700);
PAINT GREEN (-4625 3700);
DISPLAY INVISIBLE (-4625 3700);
FORCEADD DNS..1
(-7225 1425);
PAINT RED (-7225 1425);
FORCEPROP 2 LAST CDS_LIB mstr_misc
J 0
(-7225 1425);
DISPLAY INVISIBLE (-7225 1425);
FORCEPROP 1 LAST COMMENT_BODY TRUE
R 1
J 0
(-7150 1200);
DISPLAY 0.872340 (-7150 1200);
PAINT GREEN (-7150 1200);
DISPLAY INVISIBLE (-7150 1200);
FORCEADD DNS..1
(-4650 1050);
PAINT RED (-4650 1050);
FORCEPROP 2 LAST CDS_LIB mstr_misc
J 0
(-4650 1050);
DISPLAY INVISIBLE (-4650 1050);
FORCEPROP 1 LAST COMMENT_BODY TRUE
R 1
J 0
(-4575 825);
DISPLAY 0.872340 (-4575 825);
PAINT GREEN (-4575 825);
DISPLAY INVISIBLE (-4575 825);
FORCEADD DNS..1
(-4700 4450);
PAINT RED (-4700 4450);
FORCEPROP 2 LAST CDS_LIB mstr_misc
J 0
(-4700 4450);
DISPLAY INVISIBLE (-4700 4450);
FORCEPROP 1 LAST COMMENT_BODY TRUE
R 1
J 0
(-4625 4225);
DISPLAY 0.872340 (-4625 4225);
PAINT GREEN (-4625 4225);
DISPLAY INVISIBLE (-4625 4225);
FORCEADD DNS..1
(-4650 1550);
PAINT RED (-4650 1550);
FORCEPROP 2 LAST CDS_LIB mstr_misc
J 0
(-4650 1550);
DISPLAY INVISIBLE (-4650 1550);
FORCEPROP 1 LAST COMMENT_BODY TRUE
R 1
J 0
(-4575 1325);
DISPLAY 0.872340 (-4575 1325);
PAINT GREEN (-4575 1325);
DISPLAY INVISIBLE (-4575 1325);
FORCEADD DNS..1
(-7275 4325);
PAINT RED (-7275 4325);
FORCEPROP 2 LAST CDS_LIB mstr_misc
J 0
(-7275 4325);
DISPLAY INVISIBLE (-7275 4325);
FORCEPROP 1 LAST COMMENT_BODY TRUE
R 1
J 0
(-7200 4100);
DISPLAY 0.872340 (-7200 4100);
PAINT GREEN (-7200 4100);
DISPLAY INVISIBLE (-7200 4100);
FORCEADD QUANTA_TITLE_BLOCK_C..1
(0 0);
FORCEPROP 0 LAST CDS_CON_LAST_MODIFIED Fri Mar 11 14:53:33 2022
J 0
(-1885 15);
DISPLAY INVISIBLE (-1885 15);
FORCEPROP 1 LAST CUSTOM_TXT_CDS <CON_LAST_MODIFIED>
J 0
(-1885 15);
DISPLAY 0.978723 (-1885 15);
FORCEPROP 2 LAST CUSTOM_TXT_CDS <XR_PAGE_TITLE>
J 0
(-7890 5250);
DISPLAY 0.638298 (-7890 5250);
PAINT PINK (-7890 5250);
DISPLAY INVISIBLE (-7890 5250);
FORCEPROP 1 LAST CUSTOM_TXT_CDS <NAME_2>
J 0
(-3175 50);
FORCEPROP 1 LAST CUSTOM_TXT_CDS <NAME_1>
J 0
(-3175 175);
FORCEPROP 1 LAST CUSTOM_TXT_CDS <Q_NUMBER>
J 0
(-1403 103);
DISPLAY 1.212766 (-1403 103);
FORCEPROP 1 LAST CUSTOM_TXT_CDS <Q_PROJ>
J 0
(-2382 102);
DISPLAY 1.212766 (-2382 102);
FORCEPROP 1 LAST CUSTOM_TXT_CDS <Q_REV>
J 0
(-184 103);
DISPLAY 1.212766 (-184 103);
FORCEPROP 1 LAST CUSTOM_TXT_CDS <CON_PAGE_NUM> OF <CON_TOTAL_PAGES>
J 0
(-446 18);
DISPLAY 0.978723 (-446 18);
FORCEPROP 1 LAST Q_DEPT BU9
J 1
(-3763 49);
DISPLAY 1.957447 (-3763 49);
PAINT GREEN (-3763 49);
FORCEPROP 1 LAST Q_TITLE PVDDCR_CPU0_P1 VR PHASE 5&6
J 0
(-9325 50);
DISPLAY 2.446809 (-9325 50);
PAINT GREEN (-9325 50);
FORCEPROP 1 LAST CDS_LMAN_SYM_OUTLINE -9475,6775,100,-125
J 0
(0 0);
DISPLAY 0.468085 (0 0);
PAINT GREEN (0 0);
DISPLAY INVISIBLE (0 0);
FORCEPROP 2 LAST CDS_LIB pure_quanta
J 0
(0 0);
DISPLAY INVISIBLE (0 0);
FORCEPROP 2 LAST PAGE_BORDER TRUE
J 0
(-7890 5250);
DISPLAY 0.638298 (-7890 5250);
PAINT PINK (-7890 5250);
DISPLAY INVISIBLE (-7890 5250);
FORCEPROP 1 LAST COMMENT_BODY TRUE
J 0
(12 -13);
DISPLAY 0.978723 (12 -13);
PAINT GREEN (12 -13);
DISPLAY INVISIBLE (12 -13);
FORCEPROP 2 LAST CDS_XR_PAGE_TITLE CR-189 : @T6G_MB_LIB.T6G(SCH_1):PAGE189
J 0
(-7890 5250);
DISPLAY 0.638298 (-7890 5250);
PAINT PINK (-7890 5250);
DISPLAY INVISIBLE (-7890 5250);
WIRE 16 -1 (-7925 4275)(-7925 4150);
WIRE 16 -1 (-7600 4900)(-7600 4850);
WIRE 16 -1 (-7250 5475)(-7250 5350);
WIRE 16 -1 (-7375 4350)(-7600 4350);
WIRE 16 -1 (-7600 4350)(-7600 4225);
WIRE 16 -1 (-7200 2575)(-7200 2450);
WIRE 16 -1 (-7550 2000)(-7550 1950);
WIRE 16 -1 (-7325 1450)(-7550 1450);
WIRE 16 -1 (-7550 1450)(-7550 1325);
WIRE 16 -1 (-7875 1375)(-7875 1250);
WIRE 16 -1 (-4625 950)(-4625 875);
WIRE 16 -1 (-4675 3825)(-4675 3750);
WIRE 16 -1 (-3675 1875)(-3675 1850);
WIRE 16 -1 (-3675 1850)(-5650 1850);
FORCEPROP 2 LAST SIG_NAME SW_PVDDCR_CPU0_P1_PH6
J 0
(-5535 1860);
DISPLAY 0.489362 (-5535 1860);
FORCEPROP 2 LASTPROP $XRERR UNIQUE?
J 0
(-5775 1860);
DISPLAY 0.638298 (-5775 1860);
PAINT MONO (-5775 1860);
DISPLAY INVISIBLE (-5775 1860);
WIRE 16 -1 (-4625 1650)(-4625 1750);
WIRE 16 -1 (-4625 1750)(-3225 1750);
WIRE 16 -1 (-5650 1750)(-4625 1750);
FORCEPROP 2 LAST SIG_NAME SW_PVDDCR_CPU0_P1_SW6
J 0
(-5535 1760);
DISPLAY 0.489362 (-5535 1760);
FORCEPROP 2 LASTPROP $XRERR UNIQUE?
J 0
(-5775 1760);
DISPLAY 0.638298 (-5775 1760);
PAINT MONO (-5775 1760);
DISPLAY INVISIBLE (-5775 1760);
WIRE 16 -1 (-1575 4375)(-1575 4250);
WIRE 16 -1 (-1150 4250)(-1575 4250);
WIRE 16 -1 (-1150 4375)(-1150 4250);
WIRE 16 -1 (-1150 4175)(-1150 4250);
WIRE 16 -1 (-2475 4400)(-1975 4400);
FORCEPROP 2 LAST SIG_NAME IND_CPU0_P1_CPL5
J 0
(-2385 4410);
DISPLAY 0.489362 (-2385 4410);
WIRE 16 -1 (-3725 4400)(-3275 4400);
FORCEPROP 2 LAST SIG_NAME IND_CPU0_P1_CPL6
J 0
(-3710 4410);
DISPLAY 0.489362 (-3710 4410);
WIRE 16 -1 (-4600 5000)(-3725 5000);
FORCEPROP 2 LAST SIG_NAME SW_PVDDCR_CPU0_P1_BOOT5_RC
J 2
(-3760 5010);
DISPLAY 0.489362 (-3760 5010);
FORCEPROP 2 LASTPROP $XRERR UNIQUE?
J 0
(-4000 5010);
DISPLAY 0.638298 (-4000 5010);
PAINT MONO (-4000 5010);
DISPLAY INVISIBLE (-4000 5010);
WIRE 16 -1 (-3725 5000)(-3725 4975);
WIRE 16 -1 (-3725 4775)(-3725 4750);
WIRE 16 -1 (-3725 4750)(-5700 4750);
FORCEPROP 2 LAST SIG_NAME SW_PVDDCR_CPU0_P1_PH5
J 0
(-5585 4760);
DISPLAY 0.489362 (-5585 4760);
FORCEPROP 2 LASTPROP $XRERR UNIQUE?
J 0
(-5825 4760);
DISPLAY 0.638298 (-5825 4760);
PAINT MONO (-5825 4760);
DISPLAY INVISIBLE (-5825 4760);
WIRE 16 -1 (-1725 4650)(-1725 3550);
WIRE 16 -1 (-1725 4650)(-1575 4650);
WIRE 16 -1 (-2475 4650)(-1725 4650);
WIRE 16 -1 (-1725 3550)(-4225 3550);
WIRE 16 -1 (-1575 4650)(-1150 4650);
WIRE 16 -1 (-1575 4650)(-1575 4575);
WIRE 16 -1 (-1150 4750)(-1150 4650);
WIRE 16 -1 (-1150 4650)(-1150 4575);
WIRE 16 -1 (-1525 1475)(-1525 1350);
WIRE 16 -1 (-1100 1350)(-1525 1350);
WIRE 16 -1 (-1100 1475)(-1100 1350);
WIRE 16 -1 (-1100 1275)(-1100 1350);
WIRE 16 -1 (-1675 1750)(-1675 700);
WIRE 16 -1 (-2425 1750)(-1675 1750);
WIRE 16 -1 (-1675 1750)(-1525 1750);
WIRE 16 -1 (-1675 700)(-4125 700);
WIRE 16 -1 (-1525 1750)(-1100 1750);
WIRE 16 -1 (-1525 1750)(-1525 1675);
WIRE 16 -1 (-1100 1850)(-1100 1750);
WIRE 16 -1 (-1100 1750)(-1100 1675);
WIRE 16 -1 (-2425 1500)(-1925 1500);
FORCEPROP 2 LAST SIG_NAME IND_CPU0_P1_CPL6
J 0
(-2335 1510);
DISPLAY 0.489362 (-2335 1510);
WIRE 16 -1 (-4550 2100)(-3675 2100);
FORCEPROP 2 LAST SIG_NAME SW_PVDDCR_CPU0_P1_BOOT6_RC
J 2
(-3710 2110);
DISPLAY 0.489362 (-3710 2110);
FORCEPROP 2 LASTPROP $XRERR UNIQUE?
J 0
(-3950 2110);
DISPLAY 0.638298 (-3950 2110);
PAINT MONO (-3950 2110);
DISPLAY INVISIBLE (-3950 2110);
WIRE 16 -1 (-3675 2100)(-3675 2075);
WIRE 16 -1 (-3700 1500)(-3225 1500);
WIRE 16 -1 (-4100 1425)(-4100 1500);
WIRE 16 -1 (-4100 1500)(-3900 1500);
WIRE 16 -1 (-5700 4650)(-4675 4650);
FORCEPROP 2 LAST SIG_NAME SW_PVDDCR_CPU0_P1_SW5
J 0
(-5585 4660);
DISPLAY 0.489362 (-5585 4660);
FORCEPROP 2 LASTPROP $XRERR UNIQUE?
J 0
(-5825 4660);
DISPLAY 0.638298 (-5825 4660);
PAINT MONO (-5825 4660);
DISPLAY INVISIBLE (-5825 4660);
WIRE 16 -1 (-4675 4650)(-3275 4650);
WIRE 16 -1 (-4675 4550)(-4675 4650);
WIRE 16 -1 (-5350 5425)(-5350 5300);
WIRE 16 -1 (-5350 5300)(-4975 5300);
WIRE 16 -1 (-4975 5300)(-4650 5300);
WIRE 16 -1 (-4975 5425)(-4975 5300);
WIRE 16 -1 (-4650 5300)(-4325 5300);
WIRE 16 -1 (-4650 5425)(-4650 5300);
WIRE 16 -1 (-4025 5300)(-4325 5300);
WIRE 16 -1 (-4325 5425)(-4325 5300);
WIRE 16 -1 (-4025 5425)(-4025 5300);
WIRE 16 -1 (-4025 5300)(-4025 5225);
WIRE 16 -1 (-5700 5000)(-4800 5000);
FORCEPROP 2 LAST SIG_NAME SW_PVDDCR_CPU0_P1_BOOT5
J 0
(-5585 5010);
DISPLAY 0.489362 (-5585 5010);
FORCEPROP 2 LASTPROP $XRERR UNIQUE?
J 0
(-5825 5010);
DISPLAY 0.638298 (-5825 5010);
PAINT MONO (-5825 5010);
DISPLAY INVISIBLE (-5825 5010);
WIRE 16 -1 (-5600 5300)(-5600 5250);
WIRE 16 -1 (-5700 5300)(-5600 5300);
WIRE 16 -1 (-5600 5700)(-5600 5300);
WIRE 16 -1 (-5600 5250)(-5700 5250);
WIRE 16 -1 (-5600 5700)(-5350 5700);
WIRE 16 -1 (-5350 5625)(-5350 5700);
WIRE 16 -1 (-5350 5700)(-4975 5700);
WIRE 16 -1 (-4975 5700)(-4650 5700);
WIRE 16 -1 (-4975 5625)(-4975 5700);
WIRE 16 -1 (-4650 5625)(-4650 5700);
WIRE 16 -1 (-4650 5700)(-4325 5700);
WIRE 16 -1 (-4325 5700)(-4025 5700);
WIRE 16 -1 (-4325 5700)(-4325 5625);
WIRE 16 -1 (-4025 5775)(-4025 5700);
WIRE 16 -1 (-4025 5700)(-4025 5625);
WIRE 16 -1 (-5700 4300)(-5175 4300);
FORCEPROP 2 LAST SIG_NAME NC_PVDDCR_CPU0_P1_GL2_5
J 0
(-5585 4310);
DISPLAY 0.489362 (-5585 4310);
FORCEPROP 2 LASTPROP $XRERR UNIQUE?
J 0
(-5145 4300);
DISPLAY 0.638298 (-5145 4300);
PAINT MONO (-5145 4300);
DISPLAY INVISIBLE (-5145 4300);
WIRE 16 -1 (-5700 4350)(-5175 4350);
FORCEPROP 2 LAST SIG_NAME NC_PVDDCR_CPU0_P1_GL1_5
J 0
(-5585 4360);
DISPLAY 0.489362 (-5585 4360);
FORCEPROP 2 LASTPROP $XRERR UNIQUE?
J 0
(-5145 4350);
DISPLAY 0.638298 (-5145 4350);
PAINT MONO (-5145 4350);
DISPLAY INVISIBLE (-5145 4350);
WIRE 16 -1 (-6550 4400)(-7000 4400);
FORCEPROP 2 LAST SIG_NAME NC_PVDDCR_CPU0_P1_DNC5
J 2
(-6610 4410);
DISPLAY 0.489362 (-6610 4410);
FORCEPROP 2 LASTPROP $XRERR UNIQUE?
J 0
(-7240 4400);
DISPLAY 0.638298 (-7240 4400);
PAINT MONO (-7240 4400);
DISPLAY INVISIBLE (-7240 4400);
WIRE 16 -1 (-6550 4650)(-7200 4650);
FORCEPROP 2 LAST SIG_NAME PVDDCR_CPU0_P1_IMON5
J 2
(-6610 4660);
DISPLAY 0.489362 (-6610 4660);
WIRE 16 -1 (-6550 4150)(-7175 4150);
FORCEPROP 2 LAST SIG_NAME PVDDCR_CPU0_P1_TEMP0
J 2
(-6610 4160);
DISPLAY 0.489362 (-6610 4160);
WIRE 16 -1 (-7175 4350)(-6550 4350);
FORCEPROP 2 LAST SIG_NAME PVDDCR_CPU0_P1_LSET5
J 2
(-6610 4360);
DISPLAY 0.489362 (-6610 4360);
FORCEPROP 2 LASTPROP $XRERR UNIQUE?
J 0
(-6850 4360);
DISPLAY 0.638298 (-6850 4360);
PAINT MONO (-6850 4360);
DISPLAY INVISIBLE (-6850 4360);
WIRE 16 -1 (-8100 4550)(-7925 4550);
WIRE 16 -1 (-6550 4550)(-7925 4550);
FORCEPROP 2 LAST SIG_NAME PVDDCR_CPU0_P1_VCCS
J 2
(-6610 4560);
DISPLAY 0.489362 (-6610 4560);
WIRE 16 -1 (-7925 4475)(-7925 4550);
WIRE 16 -1 (-7600 5175)(-7125 5175);
WIRE 16 -1 (-7600 5450)(-7600 5175);
WIRE 16 -1 (-7600 5175)(-7600 5100);
WIRE 16 -1 (-7125 5175)(-7125 5000);
FORCEPROP 2 LAST SIG_NAME PVDDCR_CPU0_P1_VCC5
J 2
(-6610 5010);
DISPLAY 0.489362 (-6610 5010);
FORCEPROP 2 LASTPROP $XRERR UNIQUE?
J 0
(-6850 5010);
DISPLAY 0.638298 (-6850 5010);
PAINT MONO (-6850 5010);
DISPLAY INVISIBLE (-6850 5010);
WIRE 16 -1 (-7125 5000)(-6550 5000);
WIRE 16 -1 (-7125 5000)(-7125 4800);
WIRE 16 -1 (-7125 4800)(-6550 4800);
WIRE 16 -1 (-7600 5650)(-7600 5775);
WIRE 16 -1 (-7250 5775)(-7600 5775);
WIRE 16 -1 (-7600 5900)(-7600 5775);
WIRE 16 -1 (-6925 5775)(-7250 5775);
WIRE 16 -1 (-7250 5675)(-7250 5775);
WIRE 16 -1 (-6925 5300)(-6925 5775);
WIRE 16 -1 (-6925 5300)(-6550 5300);
WIRE 16 -1 (-5700 4050)(-5550 4050);
WIRE 16 -1 (-5550 4050)(-5550 4100);
WIRE 16 -1 (-5550 3975)(-5550 4050);
WIRE 16 -1 (-5550 4100)(-5550 4150);
WIRE 16 -1 (-5700 4100)(-5550 4100);
WIRE 16 -1 (-5700 4150)(-5550 4150);
WIRE 16 -1 (-5550 4200)(-5550 4150);
WIRE 16 -1 (-5550 4200)(-5700 4200);
WIRE 16 -1 (-4425 3550)(-4950 3550);
FORCEPROP 2 LAST SIG_NAME PVDDCR_CPU0_P1_VOS5
J 0
(-5585 4425);
DISPLAY 0.489362 (-5585 4425);
FORCEPROP 2 LASTPROP $XRERR UNIQUE?
J 0
(-5825 4425);
DISPLAY 0.638298 (-5825 4425);
PAINT MONO (-5825 4425);
DISPLAY INVISIBLE (-5825 4425);
WIRE 16 -1 (-4950 3550)(-4950 4400);
WIRE 16 -1 (-5700 4400)(-4950 4400);
WIRE 16 -1 (-4675 4350)(-4675 4025);
FORCEPROP 2 LAST SIG_NAME SW_PVDDCR_CPU0_P1_SW5_RC
J 0
(-4635 4160);
DISPLAY 0.489362 (-4635 4160);
FORCEPROP 2 LASTPROP $XRERR UNIQUE?
J 0
(-4875 4160);
DISPLAY 0.638298 (-4875 4160);
PAINT MONO (-4875 4160);
DISPLAY INVISIBLE (-4875 4160);
WIRE 16 -1 (-5300 2525)(-5300 2400);
WIRE 16 -1 (-5300 2400)(-4925 2400);
WIRE 16 -1 (-4925 2400)(-4600 2400);
WIRE 16 -1 (-4925 2525)(-4925 2400);
WIRE 16 -1 (-4600 2400)(-4275 2400);
WIRE 16 -1 (-4600 2525)(-4600 2400);
WIRE 16 -1 (-3975 2400)(-4275 2400);
WIRE 16 -1 (-4275 2525)(-4275 2400);
WIRE 16 -1 (-3975 2400)(-3975 2325);
WIRE 16 -1 (-3975 2525)(-3975 2400);
WIRE 16 -1 (-5650 2100)(-4750 2100);
FORCEPROP 2 LAST SIG_NAME SW_PVDDCR_CPU0_P1_BOOT6
J 0
(-5535 2110);
DISPLAY 0.489362 (-5535 2110);
FORCEPROP 2 LASTPROP $XRERR UNIQUE?
J 0
(-5775 2110);
DISPLAY 0.638298 (-5775 2110);
PAINT MONO (-5775 2110);
DISPLAY INVISIBLE (-5775 2110);
WIRE 16 -1 (-5550 2400)(-5550 2350);
WIRE 16 -1 (-5650 2400)(-5550 2400);
WIRE 16 -1 (-5550 2800)(-5550 2400);
WIRE 16 -1 (-5550 2350)(-5650 2350);
WIRE 16 -1 (-5550 2800)(-5300 2800);
WIRE 16 -1 (-5300 2800)(-4925 2800);
WIRE 16 -1 (-5300 2725)(-5300 2800);
WIRE 16 -1 (-4925 2800)(-4600 2800);
WIRE 16 -1 (-4925 2725)(-4925 2800);
WIRE 16 -1 (-4600 2800)(-4275 2800);
WIRE 16 -1 (-4600 2725)(-4600 2800);
WIRE 16 -1 (-4275 2800)(-3975 2800);
WIRE 16 -1 (-4275 2800)(-4275 2725);
WIRE 16 -1 (-3975 2875)(-3975 2800);
WIRE 16 -1 (-3975 2800)(-3975 2725);
WIRE 16 -1 (-4625 1450)(-4625 1150);
FORCEPROP 2 LAST SIG_NAME SW_PVDDCR_CPU0_P1_SW6_RC
J 0
(-4585 1260);
DISPLAY 0.489362 (-4585 1260);
FORCEPROP 2 LASTPROP $XRERR UNIQUE?
J 0
(-4825 1260);
DISPLAY 0.638298 (-4825 1260);
PAINT MONO (-4825 1260);
DISPLAY INVISIBLE (-4825 1260);
WIRE 16 -1 (-5650 1150)(-5500 1150);
WIRE 16 -1 (-5500 1150)(-5500 1200);
WIRE 16 -1 (-5500 1075)(-5500 1150);
WIRE 16 -1 (-5650 1200)(-5500 1200);
WIRE 16 -1 (-5500 1200)(-5500 1250);
WIRE 16 -1 (-5650 1250)(-5500 1250);
WIRE 16 -1 (-5500 1300)(-5500 1250);
WIRE 16 -1 (-5500 1300)(-5650 1300);
WIRE 16 -1 (-5650 1450)(-5125 1450);
FORCEPROP 2 LAST SIG_NAME NC_PVDDCR_CPU0_P1_GL1_6
J 0
(-5535 1460);
DISPLAY 0.489362 (-5535 1460);
FORCEPROP 2 LASTPROP $XRERR UNIQUE?
J 0
(-5095 1450);
DISPLAY 0.638298 (-5095 1450);
PAINT MONO (-5095 1450);
DISPLAY INVISIBLE (-5095 1450);
WIRE 16 -1 (-6550 4050)(-7150 4050);
FORCEPROP 2 LAST SIG_NAME PVDDCR_CPU0_P1_PWM5
J 2
(-6610 4060);
DISPLAY 0.489362 (-6610 4060);
WIRE 16 -1 (-7550 2750)(-7550 2875);
WIRE 16 -1 (-7200 2875)(-7550 2875);
WIRE 16 -1 (-7550 3000)(-7550 2875);
WIRE 16 -1 (-6875 2875)(-7200 2875);
WIRE 16 -1 (-7200 2775)(-7200 2875);
WIRE 16 -1 (-6875 2400)(-6875 2875);
WIRE 16 -1 (-6875 2400)(-6500 2400);
WIRE 16 -1 (-6500 1150)(-7100 1150);
FORCEPROP 2 LAST SIG_NAME PVDDCR_CPU0_P1_PWM6
J 2
(-6560 1160);
DISPLAY 0.489362 (-6560 1160);
WIRE 16 -1 (-6500 1250)(-7125 1250);
FORCEPROP 2 LAST SIG_NAME PVDDCR_CPU0_P1_TEMP0
J 2
(-6560 1260);
DISPLAY 0.489362 (-6560 1260);
WIRE 16 -1 (-6500 1750)(-7150 1750);
FORCEPROP 2 LAST SIG_NAME PVDDCR_CPU0_P1_IMON6
J 2
(-6560 1760);
DISPLAY 0.489362 (-6560 1760);
WIRE 16 -1 (-6500 1500)(-6950 1500);
FORCEPROP 2 LAST SIG_NAME NC_PVDDCR_CPU0_P1_DNC6
J 2
(-6560 1510);
DISPLAY 0.489362 (-6560 1510);
FORCEPROP 2 LASTPROP $XRERR UNIQUE?
J 0
(-7190 1500);
DISPLAY 0.638298 (-7190 1500);
PAINT MONO (-7190 1500);
DISPLAY INVISIBLE (-7190 1500);
WIRE 16 -1 (-7125 1450)(-6500 1450);
FORCEPROP 2 LAST SIG_NAME PVDDCR_CPU0_P1_LSET6
J 2
(-6560 1460);
DISPLAY 0.489362 (-6560 1460);
FORCEPROP 2 LASTPROP $XRERR UNIQUE?
J 0
(-6800 1460);
DISPLAY 0.638298 (-6800 1460);
PAINT MONO (-6800 1460);
DISPLAY INVISIBLE (-6800 1460);
WIRE 16 -1 (-5650 1400)(-5125 1400);
FORCEPROP 2 LAST SIG_NAME NC_PVDDCR_CPU0_P1_GL2_6
J 0
(-5535 1410);
DISPLAY 0.489362 (-5535 1410);
FORCEPROP 2 LASTPROP $XRERR UNIQUE?
J 0
(-5095 1400);
DISPLAY 0.638298 (-5095 1400);
PAINT MONO (-5095 1400);
DISPLAY INVISIBLE (-5095 1400);
WIRE 16 -1 (-7075 2100)(-7075 1900);
WIRE 16 -1 (-7075 2100)(-6500 2100);
WIRE 16 -1 (-7075 2275)(-7075 2100);
FORCEPROP 2 LAST SIG_NAME PVDDCR_CPU0_P1_VCC6
J 2
(-6560 2110);
DISPLAY 0.489362 (-6560 2110);
FORCEPROP 2 LASTPROP $XRERR UNIQUE?
J 0
(-6800 2110);
DISPLAY 0.638298 (-6800 2110);
PAINT MONO (-6800 2110);
DISPLAY INVISIBLE (-6800 2110);
WIRE 16 -1 (-7075 1900)(-6500 1900);
WIRE 16 -1 (-7550 2275)(-7075 2275);
WIRE 16 -1 (-7550 2550)(-7550 2275);
WIRE 16 -1 (-7550 2275)(-7550 2200);
WIRE 16 -1 (-7875 1575)(-7875 1650);
WIRE 16 -1 (-6500 1650)(-7875 1650);
FORCEPROP 2 LAST SIG_NAME PVDDCR_CPU0_P1_VCCS
J 2
(-6560 1660);
DISPLAY 0.489362 (-6560 1660);
WIRE 16 -1 (-8050 1650)(-7875 1650);
WIRE 16 -1 (-4325 700)(-4900 700);
FORCEPROP 2 LAST SIG_NAME PVDDCR_CPU0_P1_VOS6
J 0
(-5535 1525);
DISPLAY 0.489362 (-5535 1525);
FORCEPROP 2 LASTPROP $XRERR UNIQUE?
J 0
(-5775 1525);
DISPLAY 0.638298 (-5775 1525);
PAINT MONO (-5775 1525);
DISPLAY INVISIBLE (-5775 1525);
WIRE 16 -1 (-4900 1500)(-4900 700);
WIRE 16 -1 (-5650 1500)(-4900 1500);
DOT 1 (-3975 2800);
DOT 1 (-5550 2400);
DOT 1 (-4650 5700);
DOT 1 (-4975 5300);
DOT 1 (-5550 4100);
DOT 1 (-4975 5700);
DOT 1 (-7875 1650);
DOT 1 (-7550 2275);
DOT 1 (-7550 2875);
DOT 1 (-7200 2875);
DOT 1 (-5500 1250);
DOT 1 (-5300 2800);
DOT 1 (-4925 2400);
DOT 1 (-4925 2800);
DOT 1 (-4600 2800);
DOT 1 (-3975 2400);
DOT 1 (-1675 1750);
DOT 1 (-1525 1750);
DOT 1 (-1100 1350);
DOT 1 (-1100 1750);
DOT 1 (-5550 4050);
DOT 1 (-7925 4550);
DOT 1 (-7600 5175);
DOT 1 (-7600 5775);
DOT 1 (-7250 5775);
DOT 1 (-7125 5000);
DOT 1 (-5550 4150);
DOT 1 (-5600 5300);
DOT 1 (-5350 5700);
DOT 1 (-4650 5300);
DOT 1 (-4325 5300);
DOT 1 (-4325 5700);
DOT 1 (-4025 5300);
DOT 1 (-4025 5700);
DOT 1 (-1725 4650);
DOT 1 (-1575 4650);
DOT 1 (-1150 4250);
DOT 1 (-1150 4650);
DOT 1 (-4600 2400);
DOT 1 (-4675 4650);
DOT 1 (-4275 2400);
DOT 1 (-4275 2800);
DOT 1 (-5500 1200);
DOT 1 (-5500 1150);
DOT 1 (-4625 1750);
DOT 1 (-7075 2100);
FORCENOTE
PVDDCR_CPU0_P1_PHASE6
(-6650 3150) 0;
DISPLAY LEFT (-6650 3150);
DISPLAY 1.595745 (-6650 3150);
PAINT WHITE (-6650 3150);
FORCENOTE
PVDDCR_CPU0_P1_PHASE5
(-6700 6050) 0;
DISPLAY LEFT (-6700 6050);
DISPLAY 1.595745 (-6700 6050);
PAINT WHITE (-6700 6050);
FORCENOTE
DCR=2-3,0.27M OHM
(-2475 4775) 0;
DISPLAY LEFT (-2475 4775);
DISPLAY 0.638298 (-2475 4775);
PAINT WHITE (-2475 4775);
FORCENOTE
DCR=1-4,0.105M OHM
(-2475 4825) 0;
DISPLAY LEFT (-2475 4825);
DISPLAY 0.638298 (-2475 4825);
PAINT WHITE (-2475 4825);
FORCENOTE
11.0*7.5*12.5
(-2475 4875) 0;
DISPLAY LEFT (-2475 4875);
DISPLAY 0.638298 (-2475 4875);
PAINT WHITE (-2475 4875);
FORCENOTE
PGL6303.151HLT
(-2475 4975) 0;
DISPLAY LEFT (-2475 4975);
DISPLAY 0.638298 (-2475 4975);
PAINT WHITE (-2475 4975);
FORCENOTE
ISAT:70A@100C
(-2475 4925) 0;
DISPLAY LEFT (-2475 4925);
DISPLAY 0.638298 (-2475 4925);
PAINT WHITE (-2475 4925);
FORCENOTE
2ND=CV+15^0TZ01
(-2475 4725) 0;
DISPLAY LEFT (-2475 4725);
DISPLAY 0.638298 (-2475 4725);
PAINT WHITE (-2475 4725);
FORCENOTE
11.0*7.5*12.5
(-2425 1975) 0;
DISPLAY LEFT (-2425 1975);
DISPLAY 0.638298 (-2425 1975);
PAINT WHITE (-2425 1975);
FORCENOTE
DCR=1-4,0.105M OHM
(-2425 1925) 0;
DISPLAY LEFT (-2425 1925);
DISPLAY 0.638298 (-2425 1925);
PAINT WHITE (-2425 1925);
FORCENOTE
ISAT:70A@100C
(-2425 2025) 0;
DISPLAY LEFT (-2425 2025);
DISPLAY 0.638298 (-2425 2025);
PAINT WHITE (-2425 2025);
FORCENOTE
PGL6303.151HLT
(-2425 2075) 0;
DISPLAY LEFT (-2425 2075);
DISPLAY 0.638298 (-2425 2075);
PAINT WHITE (-2425 2075);
FORCENOTE
DCR=2-3,0.27M OHM
(-2425 1875) 0;
DISPLAY LEFT (-2425 1875);
DISPLAY 0.638298 (-2425 1875);
PAINT WHITE (-2425 1875);
FORCENOTE
2ND=CV+15^0TZ01
(-2425 1825) 0;
DISPLAY LEFT (-2425 1825);
DISPLAY 0.638298 (-2425 1825);
PAINT WHITE (-2425 1825);
FORCENOTE
HCME656510Q-221QL
(-3975 1450) 0;
DISPLAY LEFT (-3975 1450);
DISPLAY 0.638298 (-3975 1450);
PAINT WHITE (-3975 1450);
FORCENOTE
ISAT:30A@100C
(-3975 1400) 0;
DISPLAY LEFT (-3975 1400);
DISPLAY 0.638298 (-3975 1400);
PAINT WHITE (-3975 1400);
FORCENOTE
6.5*6.5*10.0
(-3975 1350) 0;
DISPLAY LEFT (-3975 1350);
DISPLAY 0.638298 (-3975 1350);
PAINT WHITE (-3975 1350);
FORCENOTE
DCR=0.17M OHM
(-3975 1300) 0;
DISPLAY LEFT (-3975 1300);
DISPLAY 0.638298 (-3975 1300);
PAINT WHITE (-3975 1300);
FORCENOTE
2ND=CV+22Y0EZ01
(-3975 1250) 0;
DISPLAY LEFT (-3975 1250);
DISPLAY 0.638298 (-3975 1250);
PAINT WHITE (-3975 1250);
QUIT
